FILE_TYPE = MACRO_DRAWING;
SET COLOR_WIRE YELLOW;
SET COLOR_PROP MONO;
SET COLOR_DOT WHITE;
SET COLOR_ARC YELLOW;
SET COLOR_BODY GREEN;
SET COLOR_NOTE MONO;
SET PROP_DISPLAY VALUE;
SET PAGE_NUMBER P107;
FORCEADD TAP..3
(-5525 2125);
FORCEPROP 3 LASTPIN (-5525 2075) SIG_NAME P3E_CPU0_PE1_SS_TXN<0>
J 0
(-5515 2085);
DISPLAY 0.659574 (-5515 2085);
PAINT MONO (-5515 2085);
DISPLAY INVISIBLE (-5515 2085);
FORCEPROP 1 LASTPIN (-5525 2075) BN 0
R 1
J 0
(-5532 2063);
DISPLAY 0.617021 (-5532 2063);
PAINT GREEN (-5532 2063);
FORCEPROP 2 LAST CDS_LIB mstr_standard
J 0
(-5525 2125);
PAINT ORANGE (-5525 2125);
DISPLAY INVISIBLE (-5525 2125);
FORCEPROP 1 LAST PATH I198
J 0
(-5527 2125);
DISPLAY 0.872340 (-5527 2125);
PAINT GREEN (-5527 2125);
DISPLAY INVISIBLE (-5527 2125);
FORCEPROP 1 LAST BODY_TYPE PLUMBING
J 0
(-5475 2075);
DISPLAY 2.276596 (-5475 2075);
PAINT GREEN (-5475 2075);
DISPLAY INVISIBLE (-5475 2075);
FORCEPROP 1 LAST HDL_TAP TRUE
J 0
(-5205 1995);
DISPLAY 2.276596 (-5205 1995);
PAINT GREEN (-5205 1995);
DISPLAY INVISIBLE (-5205 1995);
FORCEADD TAP..3
(-5725 2125);
FORCEPROP 3 LASTPIN (-5725 2075) SIG_NAME P3E_CPU0_PE1_SS_TXN<1>
J 0
(-5715 2085);
DISPLAY 0.659574 (-5715 2085);
PAINT MONO (-5715 2085);
DISPLAY INVISIBLE (-5715 2085);
FORCEPROP 1 LASTPIN (-5725 2075) BN 1
R 1
J 0
(-5732 2063);
DISPLAY 0.617021 (-5732 2063);
PAINT GREEN (-5732 2063);
FORCEPROP 2 LAST CDS_LIB mstr_standard
J 0
(-5725 2125);
PAINT ORANGE (-5725 2125);
DISPLAY INVISIBLE (-5725 2125);
FORCEPROP 1 LAST PATH I199
J 0
(-5727 2125);
DISPLAY 0.872340 (-5727 2125);
PAINT GREEN (-5727 2125);
DISPLAY INVISIBLE (-5727 2125);
FORCEPROP 1 LAST BODY_TYPE PLUMBING
J 0
(-5675 2075);
DISPLAY 2.276596 (-5675 2075);
PAINT GREEN (-5675 2075);
DISPLAY INVISIBLE (-5675 2075);
FORCEPROP 1 LAST HDL_TAP TRUE
J 0
(-5405 1995);
DISPLAY 2.276596 (-5405 1995);
PAINT GREEN (-5405 1995);
DISPLAY INVISIBLE (-5405 1995);
FORCEADD TAP..3
(-5925 2125);
FORCEPROP 3 LASTPIN (-5925 2075) SIG_NAME P3E_CPU0_PE1_SS_TXN<2>
J 0
(-5915 2085);
DISPLAY 0.659574 (-5915 2085);
PAINT MONO (-5915 2085);
DISPLAY INVISIBLE (-5915 2085);
FORCEPROP 1 LASTPIN (-5925 2075) BN 2
R 1
J 0
(-5932 2063);
DISPLAY 0.617021 (-5932 2063);
PAINT GREEN (-5932 2063);
FORCEPROP 2 LAST CDS_LIB mstr_standard
J 0
(-5925 2125);
PAINT ORANGE (-5925 2125);
DISPLAY INVISIBLE (-5925 2125);
FORCEPROP 1 LAST PATH I200
J 0
(-5927 2125);
DISPLAY 0.872340 (-5927 2125);
PAINT GREEN (-5927 2125);
DISPLAY INVISIBLE (-5927 2125);
FORCEPROP 1 LAST BODY_TYPE PLUMBING
J 0
(-5875 2075);
DISPLAY 2.276596 (-5875 2075);
PAINT GREEN (-5875 2075);
DISPLAY INVISIBLE (-5875 2075);
FORCEPROP 1 LAST HDL_TAP TRUE
J 0
(-5605 1995);
DISPLAY 2.276596 (-5605 1995);
PAINT GREEN (-5605 1995);
DISPLAY INVISIBLE (-5605 1995);
FORCEADD TAP..3
(-6125 2125);
FORCEPROP 3 LASTPIN (-6125 2075) SIG_NAME P3E_CPU0_PE1_SS_TXN<3>
J 0
(-6115 2085);
DISPLAY 0.659574 (-6115 2085);
PAINT MONO (-6115 2085);
DISPLAY INVISIBLE (-6115 2085);
FORCEPROP 1 LASTPIN (-6125 2075) BN 3
R 1
J 0
(-6132 2063);
DISPLAY 0.617021 (-6132 2063);
PAINT GREEN (-6132 2063);
FORCEPROP 2 LAST CDS_LIB mstr_standard
J 0
(-6125 2125);
PAINT ORANGE (-6125 2125);
DISPLAY INVISIBLE (-6125 2125);
FORCEPROP 1 LAST PATH I201
J 0
(-6127 2125);
DISPLAY 0.872340 (-6127 2125);
PAINT GREEN (-6127 2125);
DISPLAY INVISIBLE (-6127 2125);
FORCEPROP 1 LAST BODY_TYPE PLUMBING
J 0
(-6075 2075);
DISPLAY 2.276596 (-6075 2075);
PAINT GREEN (-6075 2075);
DISPLAY INVISIBLE (-6075 2075);
FORCEPROP 1 LAST HDL_TAP TRUE
J 0
(-5805 1995);
DISPLAY 2.276596 (-5805 1995);
PAINT GREEN (-5805 1995);
DISPLAY INVISIBLE (-5805 1995);
FORCEADD TAP..3
(-6325 2125);
FORCEPROP 3 LASTPIN (-6325 2075) SIG_NAME P3E_CPU0_PE1_SS_TXN<4>
J 0
(-6315 2085);
DISPLAY 0.659574 (-6315 2085);
PAINT MONO (-6315 2085);
DISPLAY INVISIBLE (-6315 2085);
FORCEPROP 1 LASTPIN (-6325 2075) BN 4
R 1
J 0
(-6332 2063);
DISPLAY 0.617021 (-6332 2063);
PAINT GREEN (-6332 2063);
FORCEPROP 2 LAST CDS_LIB mstr_standard
J 0
(-6325 2125);
PAINT ORANGE (-6325 2125);
DISPLAY INVISIBLE (-6325 2125);
FORCEPROP 1 LAST PATH I202
J 0
(-6327 2125);
DISPLAY 0.872340 (-6327 2125);
PAINT GREEN (-6327 2125);
DISPLAY INVISIBLE (-6327 2125);
FORCEPROP 1 LAST BODY_TYPE PLUMBING
J 0
(-6275 2075);
DISPLAY 2.276596 (-6275 2075);
PAINT GREEN (-6275 2075);
DISPLAY INVISIBLE (-6275 2075);
FORCEPROP 1 LAST HDL_TAP TRUE
J 0
(-6005 1995);
DISPLAY 2.276596 (-6005 1995);
PAINT GREEN (-6005 1995);
DISPLAY INVISIBLE (-6005 1995);
FORCEADD TAP..3
(-6525 2125);
FORCEPROP 3 LASTPIN (-6525 2075) SIG_NAME P3E_CPU0_PE1_SS_TXN<5>
J 0
(-6515 2085);
DISPLAY 0.659574 (-6515 2085);
PAINT MONO (-6515 2085);
DISPLAY INVISIBLE (-6515 2085);
FORCEPROP 1 LASTPIN (-6525 2075) BN 5
R 1
J 0
(-6532 2063);
DISPLAY 0.617021 (-6532 2063);
PAINT GREEN (-6532 2063);
FORCEPROP 2 LAST CDS_LIB mstr_standard
J 0
(-6525 2125);
PAINT ORANGE (-6525 2125);
DISPLAY INVISIBLE (-6525 2125);
FORCEPROP 1 LAST PATH I203
J 0
(-6527 2125);
DISPLAY 0.872340 (-6527 2125);
PAINT GREEN (-6527 2125);
DISPLAY INVISIBLE (-6527 2125);
FORCEPROP 1 LAST BODY_TYPE PLUMBING
J 0
(-6475 2075);
DISPLAY 2.276596 (-6475 2075);
PAINT GREEN (-6475 2075);
DISPLAY INVISIBLE (-6475 2075);
FORCEPROP 1 LAST HDL_TAP TRUE
J 0
(-6205 1995);
DISPLAY 2.276596 (-6205 1995);
PAINT GREEN (-6205 1995);
DISPLAY INVISIBLE (-6205 1995);
FORCEADD TAP..3
(-6725 2125);
FORCEPROP 3 LASTPIN (-6725 2075) SIG_NAME P3E_CPU0_PE1_SS_TXN<6>
J 0
(-6715 2085);
DISPLAY 0.659574 (-6715 2085);
PAINT MONO (-6715 2085);
DISPLAY INVISIBLE (-6715 2085);
FORCEPROP 1 LASTPIN (-6725 2075) BN 6
R 1
J 0
(-6732 2063);
DISPLAY 0.617021 (-6732 2063);
PAINT GREEN (-6732 2063);
FORCEPROP 2 LAST CDS_LIB mstr_standard
J 0
(-6725 2125);
PAINT ORANGE (-6725 2125);
DISPLAY INVISIBLE (-6725 2125);
FORCEPROP 1 LAST PATH I204
J 0
(-6727 2125);
DISPLAY 0.872340 (-6727 2125);
PAINT GREEN (-6727 2125);
DISPLAY INVISIBLE (-6727 2125);
FORCEPROP 1 LAST BODY_TYPE PLUMBING
J 0
(-6675 2075);
DISPLAY 2.276596 (-6675 2075);
PAINT GREEN (-6675 2075);
DISPLAY INVISIBLE (-6675 2075);
FORCEPROP 1 LAST HDL_TAP TRUE
J 0
(-6405 1995);
DISPLAY 2.276596 (-6405 1995);
PAINT GREEN (-6405 1995);
DISPLAY INVISIBLE (-6405 1995);
FORCEADD TAP..3
(-6925 2125);
FORCEPROP 3 LASTPIN (-6925 2075) SIG_NAME P3E_CPU0_PE1_SS_TXN<7>
J 0
(-6915 2085);
DISPLAY 0.659574 (-6915 2085);
PAINT MONO (-6915 2085);
DISPLAY INVISIBLE (-6915 2085);
FORCEPROP 1 LASTPIN (-6925 2075) BN 7
R 1
J 0
(-6932 2063);
DISPLAY 0.617021 (-6932 2063);
PAINT GREEN (-6932 2063);
FORCEPROP 2 LAST CDS_LIB mstr_standard
J 0
(-6925 2125);
PAINT ORANGE (-6925 2125);
DISPLAY INVISIBLE (-6925 2125);
FORCEPROP 1 LAST PATH I205
J 0
(-6927 2125);
DISPLAY 0.872340 (-6927 2125);
PAINT GREEN (-6927 2125);
DISPLAY INVISIBLE (-6927 2125);
FORCEPROP 1 LAST BODY_TYPE PLUMBING
J 0
(-6875 2075);
DISPLAY 2.276596 (-6875 2075);
PAINT GREEN (-6875 2075);
DISPLAY INVISIBLE (-6875 2075);
FORCEPROP 1 LAST HDL_TAP TRUE
J 0
(-6605 1995);
DISPLAY 2.276596 (-6605 1995);
PAINT GREEN (-6605 1995);
DISPLAY INVISIBLE (-6605 1995);
FORCEADD OFFPAGE..1
(-7100 2175);
FORCEPROP 2 LAST $XR1 107 
J 0
(-7441 2175);
DISPLAY 0.638298 (-7441 2175);
PAINT MONO (-7441 2175);
FORCEPROP 2 LAST $XR0 30 
J 0
(-7321 2175);
DISPLAY 0.638298 (-7321 2175);
PAINT MONO (-7321 2175);
FORCEPROP 2 LAST PATH I206
J 0
(-7050 2250);
DISPLAY 1.021277 (-7050 2250);
PAINT ORANGE (-7050 2250);
DISPLAY INVISIBLE (-7050 2250);
FORCEPROP 2 LAST CDS_LIB mstr_standard
J 0
(-7100 2175);
PAINT ORANGE (-7100 2175);
DISPLAY INVISIBLE (-7100 2175);
FORCEPROP 1 LAST OFFPAGE TRUE
J 0
(-6780 2045);
PAINT GREEN (-6780 2045);
DISPLAY INVISIBLE (-6780 2045);
FORCEPROP 1 LAST COMMENT_BODY TRUE
J 0
(-6980 2075);
DISPLAY 2.276596 (-6980 2075);
PAINT GREEN (-6980 2075);
DISPLAY INVISIBLE (-6980 2075);
FORCEADD CAP..1
R 2
(-5525 1875);
FORCEPROP 0 LAST GROUP PCIE_UPLINK
J 0
(-5682 2120);
DISPLAY 0.638298 (-5682 2120);
PAINT BROWN (-5682 2120);
DISPLAY BOTH (-5682 2120);
FORCEPROP 1 LAST TOLERANCE 10%
J 2
(-5575 1825);
DISPLAY 0.617021 (-5575 1825);
PAINT SKYBLUE (-5575 1825);
FORCEPROP 1 LAST LOCATION C3P13
J 2
(-5575 1975);
DISPLAY 0.617021 (-5575 1975);
PAINT AQUA (-5575 1975);
FORCEPROP 1 LAST VALUE 0.22UF
J 2
(-5575 1925);
DISPLAY 0.617021 (-5575 1925);
PAINT SKYBLUE (-5575 1925);
FORCEPROP 1 LAST VOLTAGE 16V
J 2
(-5575 1875);
DISPLAY 0.617021 (-5575 1875);
PAINT SKYBLUE (-5575 1875);
FORCEPROP 1 LAST PACK_TYPE 0402
J 2
(-5575 1675);
DISPLAY 0.617021 (-5575 1675);
PAINT SKYBLUE (-5575 1675);
FORCEPROP 1 LAST MATERIAL X7R
J 2
(-5575 1775);
DISPLAY 0.617021 (-5575 1775);
PAINT SKYBLUE (-5575 1775);
FORCEPROP 1 LAST PART_NUMBER A36096-155
J 2
(-5575 1725);
DISPLAY 0.617021 (-5575 1725);
PAINT BLUE (-5575 1725);
FORCEPROP 1 LASTPIN (-5525 1775) $PN 2
J 2
(-5535 1755);
DISPLAY 0.787234 (-5535 1755);
PAINT ORANGE (-5535 1755);
DISPLAY INVISIBLE (-5535 1755);
FORCEPROP 1 LASTPIN (-5525 1975) $PN 1
J 2
(-5535 1955);
DISPLAY 0.787234 (-5535 1955);
PAINT ORANGE (-5535 1955);
DISPLAY INVISIBLE (-5535 1955);
FORCEPROP 2 LAST CDS_LIB mstr_discrete
J 0
(-5525 1875);
PAINT ORANGE (-5525 1875);
DISPLAY INVISIBLE (-5525 1875);
FORCEPROP 2 LAST CDS_LOCATION C3P13
J 2
(-5575 1975);
DISPLAY 0.617021 (-5575 1975);
PAINT AQUA (-5575 1975);
DISPLAY INVISIBLE (-5575 1975);
FORCEPROP 1 LAST PATH I207
J 2
(-5575 2025);
DISPLAY 0.978723 (-5575 2025);
PAINT WHITE (-5575 2025);
DISPLAY INVISIBLE (-5575 2025);
FORCEPROP 2 LAST CDS_SEC 1
J 0
(-5575 2075);
DISPLAY 1.021277 (-5575 2075);
PAINT ORANGE (-5575 2075);
DISPLAY INVISIBLE (-5575 2075);
FORCEPROP 2 LAST $SEC 1
J 0
(-5575 2075);
DISPLAY 0.680851 (-5575 2075);
PAINT MONO (-5575 2075);
DISPLAY INVISIBLE (-5575 2075);
FORCEADD CAP..1
R 2
(-5725 1575);
FORCEPROP 1 LAST PART_NUMBER A36096-155
J 2
(-5775 1425);
DISPLAY 0.617021 (-5775 1425);
PAINT BLUE (-5775 1425);
FORCEPROP 1 LAST TOLERANCE 10%
J 2
(-5775 1525);
DISPLAY 0.617021 (-5775 1525);
PAINT SKYBLUE (-5775 1525);
FORCEPROP 1 LAST MATERIAL X7R
J 2
(-5775 1475);
DISPLAY 0.617021 (-5775 1475);
PAINT SKYBLUE (-5775 1475);
FORCEPROP 1 LAST VALUE 0.22UF
J 2
(-5775 1625);
DISPLAY 0.617021 (-5775 1625);
PAINT SKYBLUE (-5775 1625);
FORCEPROP 1 LAST VOLTAGE 16V
J 2
(-5775 1575);
DISPLAY 0.617021 (-5775 1575);
PAINT SKYBLUE (-5775 1575);
FORCEPROP 1 LAST PACK_TYPE 0402
J 2
(-5775 1375);
DISPLAY 0.617021 (-5775 1375);
PAINT SKYBLUE (-5775 1375);
FORCEPROP 1 LAST LOCATION C3P17
J 2
(-5775 1675);
DISPLAY 0.617021 (-5775 1675);
PAINT AQUA (-5775 1675);
FORCEPROP 0 LAST GROUP PCIE_UPLINK
J 0
(-5882 1295);
DISPLAY 0.638298 (-5882 1295);
PAINT BROWN (-5882 1295);
DISPLAY BOTH (-5882 1295);
FORCEPROP 1 LASTPIN (-5725 1475) $PN 2
J 2
(-5735 1455);
DISPLAY 0.787234 (-5735 1455);
PAINT ORANGE (-5735 1455);
DISPLAY INVISIBLE (-5735 1455);
FORCEPROP 1 LASTPIN (-5725 1675) $PN 1
J 2
(-5735 1655);
DISPLAY 0.787234 (-5735 1655);
PAINT ORANGE (-5735 1655);
DISPLAY INVISIBLE (-5735 1655);
FORCEPROP 2 LAST CDS_LIB mstr_discrete
J 0
(-5725 1575);
PAINT ORANGE (-5725 1575);
DISPLAY INVISIBLE (-5725 1575);
FORCEPROP 2 LAST CDS_SEC 1
J 0
(-5775 1775);
DISPLAY 1.021277 (-5775 1775);
PAINT ORANGE (-5775 1775);
DISPLAY INVISIBLE (-5775 1775);
FORCEPROP 2 LAST $SEC 1
J 0
(-5775 1775);
DISPLAY 0.680851 (-5775 1775);
PAINT MONO (-5775 1775);
DISPLAY INVISIBLE (-5775 1775);
FORCEPROP 2 LAST CDS_LOCATION C3P17
J 2
(-5775 1675);
DISPLAY 0.617021 (-5775 1675);
PAINT AQUA (-5775 1675);
DISPLAY INVISIBLE (-5775 1675);
FORCEPROP 1 LAST PATH I208
J 2
(-5775 1725);
DISPLAY 0.978723 (-5775 1725);
PAINT WHITE (-5775 1725);
DISPLAY INVISIBLE (-5775 1725);
FORCEADD OFFPAGE..2
(-5275 1275);
FORCEPROP 2 LAST $XR0 117 
J 0
(-5086 1275);
DISPLAY 0.638298 (-5086 1275);
PAINT MONO (-5086 1275);
FORCEPROP 2 LAST CDS_LIB mstr_standard
J 0
(-5275 1275);
PAINT ORANGE (-5275 1275);
DISPLAY INVISIBLE (-5275 1275);
FORCEPROP 2 LAST PATH I209
J 0
(-5100 1350);
DISPLAY 1.021277 (-5100 1350);
PAINT ORANGE (-5100 1350);
DISPLAY INVISIBLE (-5100 1350);
FORCEPROP 1 LAST OFFPAGE TRUE
J 0
(-4950 1150);
DISPLAY 0.872340 (-4950 1150);
PAINT GREEN (-4950 1150);
DISPLAY INVISIBLE (-4950 1150);
FORCEPROP 1 LAST COMMENT_BODY TRUE
J 0
(-5320 1180);
DISPLAY 0.872340 (-5320 1180);
PAINT GREEN (-5320 1180);
DISPLAY INVISIBLE (-5320 1180);
FORCEADD TAP..7
(-5525 1325);
FORCEPROP 3 LASTPIN (-5525 1375) SIG_NAME P3E_CPU0_PE1_PCH_TXN<0>
J 0
(-5515 1385);
DISPLAY 0.659574 (-5515 1385);
PAINT MONO (-5515 1385);
DISPLAY INVISIBLE (-5515 1385);
FORCEPROP 1 LASTPIN (-5525 1375) BN 0
R 1
J 0
(-5532 1323);
DISPLAY 0.617021 (-5532 1323);
PAINT GREEN (-5532 1323);
FORCEPROP 2 LAST CDS_LIB mstr_standard
J 0
(-5525 1325);
PAINT ORANGE (-5525 1325);
DISPLAY INVISIBLE (-5525 1325);
FORCEPROP 1 LAST PATH I210
J 0
(-5527 1325);
DISPLAY 0.872340 (-5527 1325);
PAINT GREEN (-5527 1325);
DISPLAY INVISIBLE (-5527 1325);
FORCEPROP 1 LAST BODY_TYPE PLUMBING
J 0
(-5475 1325);
DISPLAY 2.276596 (-5475 1325);
PAINT GREEN (-5475 1325);
DISPLAY INVISIBLE (-5475 1325);
FORCEPROP 1 LAST HDL_TAP TRUE
J 0
(-5205 1195);
DISPLAY 2.276596 (-5205 1195);
PAINT GREEN (-5205 1195);
DISPLAY INVISIBLE (-5205 1195);
FORCEADD TAP..3
(-5475 1125);
FORCEPROP 3 LASTPIN (-5475 1075) SIG_NAME P3E_CPU0_PE1_SS_TXP<0>
J 0
(-5465 1085);
DISPLAY 0.659574 (-5465 1085);
PAINT MONO (-5465 1085);
DISPLAY INVISIBLE (-5465 1085);
FORCEPROP 1 LASTPIN (-5475 1075) BN 0
R 1
J 0
(-5482 1063);
DISPLAY 0.617021 (-5482 1063);
PAINT GREEN (-5482 1063);
FORCEPROP 1 LAST PATH I211
J 0
(-5477 1125);
DISPLAY 0.872340 (-5477 1125);
PAINT GREEN (-5477 1125);
DISPLAY INVISIBLE (-5477 1125);
FORCEPROP 2 LAST CDS_LIB mstr_standard
J 0
(-5475 1125);
PAINT ORANGE (-5475 1125);
DISPLAY INVISIBLE (-5475 1125);
FORCEPROP 1 LAST BODY_TYPE PLUMBING
J 0
(-5425 1075);
DISPLAY 2.276596 (-5425 1075);
PAINT GREEN (-5425 1075);
DISPLAY INVISIBLE (-5425 1075);
FORCEPROP 1 LAST HDL_TAP TRUE
J 0
(-5155 995);
DISPLAY 2.276596 (-5155 995);
PAINT GREEN (-5155 995);
DISPLAY INVISIBLE (-5155 995);
FORCEADD CAP..1
R 2
(-5475 875);
FORCEPROP 1 LAST VOLTAGE 16V
J 2
(-5525 875);
DISPLAY 0.617021 (-5525 875);
PAINT SKYBLUE (-5525 875);
FORCEPROP 1 LAST VALUE 0.22UF
J 2
(-5525 925);
DISPLAY 0.617021 (-5525 925);
PAINT SKYBLUE (-5525 925);
FORCEPROP 1 LAST PART_NUMBER A36096-155
J 2
(-5525 725);
DISPLAY 0.617021 (-5525 725);
PAINT BLUE (-5525 725);
FORCEPROP 1 LAST PACK_TYPE 0402
J 2
(-5525 675);
DISPLAY 0.617021 (-5525 675);
PAINT SKYBLUE (-5525 675);
FORCEPROP 1 LAST TOLERANCE 10%
J 2
(-5525 825);
DISPLAY 0.617021 (-5525 825);
PAINT SKYBLUE (-5525 825);
FORCEPROP 1 LAST MATERIAL X7R
J 2
(-5525 775);
DISPLAY 0.617021 (-5525 775);
PAINT SKYBLUE (-5525 775);
FORCEPROP 1 LAST LOCATION C3P11
J 2
(-5525 975);
DISPLAY 0.617021 (-5525 975);
PAINT AQUA (-5525 975);
FORCEPROP 0 LAST GROUP PCIE_UPLINK
J 0
(-5657 1120);
DISPLAY 0.638298 (-5657 1120);
PAINT BROWN (-5657 1120);
DISPLAY BOTH (-5657 1120);
FORCEPROP 1 LASTPIN (-5475 775) $PN 2
J 2
(-5485 755);
DISPLAY 0.787234 (-5485 755);
PAINT ORANGE (-5485 755);
DISPLAY INVISIBLE (-5485 755);
FORCEPROP 1 LASTPIN (-5475 975) $PN 1
J 2
(-5485 955);
DISPLAY 0.787234 (-5485 955);
PAINT ORANGE (-5485 955);
DISPLAY INVISIBLE (-5485 955);
FORCEPROP 2 LAST CDS_LIB mstr_discrete
J 0
(-5475 875);
PAINT ORANGE (-5475 875);
DISPLAY INVISIBLE (-5475 875);
FORCEPROP 2 LAST CDS_LOCATION C3P11
J 2
(-5525 975);
DISPLAY 0.617021 (-5525 975);
PAINT AQUA (-5525 975);
DISPLAY INVISIBLE (-5525 975);
FORCEPROP 2 LAST CDS_SEC 1
J 0
(-5525 1075);
DISPLAY 1.021277 (-5525 1075);
PAINT ORANGE (-5525 1075);
DISPLAY INVISIBLE (-5525 1075);
FORCEPROP 2 LAST $SEC 1
J 0
(-5525 1075);
DISPLAY 0.680851 (-5525 1075);
PAINT MONO (-5525 1075);
DISPLAY INVISIBLE (-5525 1075);
FORCEPROP 1 LAST PATH I212
J 2
(-5525 1025);
DISPLAY 0.978723 (-5525 1025);
PAINT WHITE (-5525 1025);
DISPLAY INVISIBLE (-5525 1025);
FORCEADD TAP..7
(-5725 1325);
FORCEPROP 3 LASTPIN (-5725 1375) SIG_NAME P3E_CPU0_PE1_PCH_TXN<1>
J 0
(-5715 1385);
DISPLAY 0.659574 (-5715 1385);
PAINT MONO (-5715 1385);
DISPLAY INVISIBLE (-5715 1385);
FORCEPROP 1 LASTPIN (-5725 1375) BN 1
R 1
J 0
(-5732 1323);
DISPLAY 0.617021 (-5732 1323);
PAINT GREEN (-5732 1323);
FORCEPROP 2 LAST CDS_LIB mstr_standard
J 0
(-5725 1325);
PAINT ORANGE (-5725 1325);
DISPLAY INVISIBLE (-5725 1325);
FORCEPROP 1 LAST PATH I213
J 0
(-5727 1325);
DISPLAY 0.872340 (-5727 1325);
PAINT GREEN (-5727 1325);
DISPLAY INVISIBLE (-5727 1325);
FORCEPROP 1 LAST BODY_TYPE PLUMBING
J 0
(-5675 1325);
DISPLAY 2.276596 (-5675 1325);
PAINT GREEN (-5675 1325);
DISPLAY INVISIBLE (-5675 1325);
FORCEPROP 1 LAST HDL_TAP TRUE
J 0
(-5405 1195);
DISPLAY 2.276596 (-5405 1195);
PAINT GREEN (-5405 1195);
DISPLAY INVISIBLE (-5405 1195);
FORCEADD TAP..3
(-5675 1125);
FORCEPROP 3 LASTPIN (-5675 1075) SIG_NAME P3E_CPU0_PE1_SS_TXP<1>
J 0
(-5665 1085);
DISPLAY 0.659574 (-5665 1085);
PAINT MONO (-5665 1085);
DISPLAY INVISIBLE (-5665 1085);
FORCEPROP 1 LASTPIN (-5675 1075) BN 1
R 1
J 0
(-5682 1063);
DISPLAY 0.617021 (-5682 1063);
PAINT GREEN (-5682 1063);
FORCEPROP 1 LAST PATH I214
J 0
(-5677 1125);
DISPLAY 0.872340 (-5677 1125);
PAINT GREEN (-5677 1125);
DISPLAY INVISIBLE (-5677 1125);
FORCEPROP 2 LAST CDS_LIB mstr_standard
J 0
(-5675 1125);
PAINT ORANGE (-5675 1125);
DISPLAY INVISIBLE (-5675 1125);
FORCEPROP 1 LAST BODY_TYPE PLUMBING
J 0
(-5625 1075);
DISPLAY 2.276596 (-5625 1075);
PAINT GREEN (-5625 1075);
DISPLAY INVISIBLE (-5625 1075);
FORCEPROP 1 LAST HDL_TAP TRUE
J 0
(-5355 995);
DISPLAY 2.276596 (-5355 995);
PAINT GREEN (-5355 995);
DISPLAY INVISIBLE (-5355 995);
FORCEADD CAP..1
R 2
(-5925 1900);
FORCEPROP 1 LAST PACK_TYPE 0402
J 2
(-5975 1700);
DISPLAY 0.617021 (-5975 1700);
PAINT SKYBLUE (-5975 1700);
FORCEPROP 1 LAST VOLTAGE 16V
J 2
(-5975 1900);
DISPLAY 0.617021 (-5975 1900);
PAINT SKYBLUE (-5975 1900);
FORCEPROP 1 LAST PART_NUMBER A36096-155
J 2
(-5975 1750);
DISPLAY 0.617021 (-5975 1750);
PAINT BLUE (-5975 1750);
FORCEPROP 1 LAST MATERIAL X7R
J 2
(-5975 1800);
DISPLAY 0.617021 (-5975 1800);
PAINT SKYBLUE (-5975 1800);
FORCEPROP 1 LAST TOLERANCE 10%
J 2
(-5975 1850);
DISPLAY 0.617021 (-5975 1850);
PAINT SKYBLUE (-5975 1850);
FORCEPROP 1 LAST VALUE 0.22UF
J 2
(-5975 1950);
DISPLAY 0.617021 (-5975 1950);
PAINT SKYBLUE (-5975 1950);
FORCEPROP 1 LAST LOCATION C3P20
J 2
(-5975 2000);
DISPLAY 0.617021 (-5975 2000);
PAINT AQUA (-5975 2000);
FORCEPROP 0 LAST GROUP PCIE_UPLINK
J 0
(-6107 2120);
DISPLAY 0.638298 (-6107 2120);
PAINT BROWN (-6107 2120);
DISPLAY BOTH (-6107 2120);
FORCEPROP 1 LASTPIN (-5925 1800) $PN 2
J 2
(-5935 1780);
DISPLAY 0.787234 (-5935 1780);
PAINT ORANGE (-5935 1780);
DISPLAY INVISIBLE (-5935 1780);
FORCEPROP 1 LASTPIN (-5925 2000) $PN 1
J 2
(-5935 1980);
DISPLAY 0.787234 (-5935 1980);
PAINT ORANGE (-5935 1980);
DISPLAY INVISIBLE (-5935 1980);
FORCEPROP 2 LAST CDS_LOCATION C3P20
J 2
(-5975 2000);
DISPLAY 0.617021 (-5975 2000);
PAINT AQUA (-5975 2000);
DISPLAY INVISIBLE (-5975 2000);
FORCEPROP 2 LAST CDS_LIB mstr_discrete
J 0
(-5925 1900);
PAINT ORANGE (-5925 1900);
DISPLAY INVISIBLE (-5925 1900);
FORCEPROP 2 LAST CDS_SEC 1
J 0
(-5975 2100);
DISPLAY 1.021277 (-5975 2100);
PAINT ORANGE (-5975 2100);
DISPLAY INVISIBLE (-5975 2100);
FORCEPROP 2 LAST $SEC 1
J 0
(-5975 2100);
DISPLAY 0.680851 (-5975 2100);
PAINT MONO (-5975 2100);
DISPLAY INVISIBLE (-5975 2100);
FORCEPROP 1 LAST PATH I215
J 2
(-5975 2050);
DISPLAY 0.978723 (-5975 2050);
PAINT WHITE (-5975 2050);
DISPLAY INVISIBLE (-5975 2050);
FORCEADD CAP..1
R 2
(-6125 1575);
FORCEPROP 1 LAST MATERIAL X7R
J 2
(-6175 1475);
DISPLAY 0.617021 (-6175 1475);
PAINT SKYBLUE (-6175 1475);
FORCEPROP 1 LAST VALUE 0.22UF
J 2
(-6175 1625);
DISPLAY 0.617021 (-6175 1625);
PAINT SKYBLUE (-6175 1625);
FORCEPROP 1 LAST LOCATION C3P25
J 2
(-6175 1675);
DISPLAY 0.617021 (-6175 1675);
PAINT AQUA (-6175 1675);
FORCEPROP 1 LAST PACK_TYPE 0402
J 2
(-6175 1375);
DISPLAY 0.617021 (-6175 1375);
PAINT SKYBLUE (-6175 1375);
FORCEPROP 1 LAST VOLTAGE 16V
J 2
(-6175 1575);
DISPLAY 0.617021 (-6175 1575);
PAINT SKYBLUE (-6175 1575);
FORCEPROP 1 LAST PART_NUMBER A36096-155
J 2
(-6175 1425);
DISPLAY 0.617021 (-6175 1425);
PAINT BLUE (-6175 1425);
FORCEPROP 1 LAST TOLERANCE 10%
J 2
(-6175 1525);
DISPLAY 0.617021 (-6175 1525);
PAINT SKYBLUE (-6175 1525);
FORCEPROP 0 LAST GROUP PCIE_UPLINK
J 0
(-6282 1295);
DISPLAY 0.638298 (-6282 1295);
PAINT BROWN (-6282 1295);
DISPLAY BOTH (-6282 1295);
FORCEPROP 1 LAST PATH I216
J 2
(-6175 1725);
DISPLAY 0.978723 (-6175 1725);
PAINT WHITE (-6175 1725);
DISPLAY INVISIBLE (-6175 1725);
FORCEPROP 2 LAST CDS_LOCATION C3P25
J 2
(-6175 1675);
DISPLAY 0.617021 (-6175 1675);
PAINT AQUA (-6175 1675);
DISPLAY INVISIBLE (-6175 1675);
FORCEPROP 2 LAST $SEC 1
J 0
(-6175 1775);
DISPLAY 0.680851 (-6175 1775);
PAINT MONO (-6175 1775);
DISPLAY INVISIBLE (-6175 1775);
FORCEPROP 2 LAST CDS_SEC 1
J 0
(-6175 1775);
DISPLAY 1.021277 (-6175 1775);
PAINT ORANGE (-6175 1775);
DISPLAY INVISIBLE (-6175 1775);
FORCEPROP 1 LASTPIN (-6125 1475) $PN 2
J 2
(-6135 1455);
DISPLAY 0.787234 (-6135 1455);
PAINT ORANGE (-6135 1455);
DISPLAY INVISIBLE (-6135 1455);
FORCEPROP 1 LASTPIN (-6125 1675) $PN 1
J 2
(-6135 1655);
DISPLAY 0.787234 (-6135 1655);
PAINT ORANGE (-6135 1655);
DISPLAY INVISIBLE (-6135 1655);
FORCEPROP 2 LAST CDS_LIB mstr_discrete
J 0
(-6125 1575);
PAINT ORANGE (-6125 1575);
DISPLAY INVISIBLE (-6125 1575);
FORCEADD TAP..7
(-5925 1325);
FORCEPROP 3 LASTPIN (-5925 1375) SIG_NAME P3E_CPU0_PE1_PCH_TXN<2>
J 0
(-5915 1385);
DISPLAY 0.659574 (-5915 1385);
PAINT MONO (-5915 1385);
DISPLAY INVISIBLE (-5915 1385);
FORCEPROP 1 LASTPIN (-5925 1375) BN 2
R 1
J 0
(-5932 1323);
DISPLAY 0.617021 (-5932 1323);
PAINT GREEN (-5932 1323);
FORCEPROP 1 LAST PATH I217
J 0
(-5927 1325);
DISPLAY 0.872340 (-5927 1325);
PAINT GREEN (-5927 1325);
DISPLAY INVISIBLE (-5927 1325);
FORCEPROP 2 LAST CDS_LIB mstr_standard
J 0
(-5925 1325);
PAINT ORANGE (-5925 1325);
DISPLAY INVISIBLE (-5925 1325);
FORCEPROP 1 LAST BODY_TYPE PLUMBING
J 0
(-5875 1325);
DISPLAY 2.276596 (-5875 1325);
PAINT GREEN (-5875 1325);
DISPLAY INVISIBLE (-5875 1325);
FORCEPROP 1 LAST HDL_TAP TRUE
J 0
(-5605 1195);
DISPLAY 2.276596 (-5605 1195);
PAINT GREEN (-5605 1195);
DISPLAY INVISIBLE (-5605 1195);
FORCEADD TAP..3
(-5875 1125);
FORCEPROP 3 LASTPIN (-5875 1075) SIG_NAME P3E_CPU0_PE1_SS_TXP<2>
J 0
(-5865 1085);
DISPLAY 0.659574 (-5865 1085);
PAINT MONO (-5865 1085);
DISPLAY INVISIBLE (-5865 1085);
FORCEPROP 1 LASTPIN (-5875 1075) BN 2
R 1
J 0
(-5882 1063);
DISPLAY 0.617021 (-5882 1063);
PAINT GREEN (-5882 1063);
FORCEPROP 1 LAST PATH I218
J 0
(-5877 1125);
DISPLAY 0.872340 (-5877 1125);
PAINT GREEN (-5877 1125);
DISPLAY INVISIBLE (-5877 1125);
FORCEPROP 2 LAST CDS_LIB mstr_standard
J 0
(-5875 1125);
PAINT ORANGE (-5875 1125);
DISPLAY INVISIBLE (-5875 1125);
FORCEPROP 1 LAST BODY_TYPE PLUMBING
J 0
(-5825 1075);
DISPLAY 2.276596 (-5825 1075);
PAINT GREEN (-5825 1075);
DISPLAY INVISIBLE (-5825 1075);
FORCEPROP 1 LAST HDL_TAP TRUE
J 0
(-5555 995);
DISPLAY 2.276596 (-5555 995);
PAINT GREEN (-5555 995);
DISPLAY INVISIBLE (-5555 995);
FORCEADD CAP..1
R 2
(-5875 875);
FORCEPROP 1 LAST LOCATION C3P18
J 2
(-5925 975);
DISPLAY 0.617021 (-5925 975);
PAINT AQUA (-5925 975);
FORCEPROP 1 LAST PART_NUMBER A36096-155
J 2
(-5925 725);
DISPLAY 0.617021 (-5925 725);
PAINT BLUE (-5925 725);
FORCEPROP 1 LAST PACK_TYPE 0402
J 2
(-5925 675);
DISPLAY 0.617021 (-5925 675);
PAINT SKYBLUE (-5925 675);
FORCEPROP 1 LAST MATERIAL X7R
J 2
(-5925 775);
DISPLAY 0.617021 (-5925 775);
PAINT SKYBLUE (-5925 775);
FORCEPROP 1 LAST VOLTAGE 16V
J 2
(-5925 875);
DISPLAY 0.617021 (-5925 875);
PAINT SKYBLUE (-5925 875);
FORCEPROP 1 LAST TOLERANCE 10%
J 2
(-5925 825);
DISPLAY 0.617021 (-5925 825);
PAINT SKYBLUE (-5925 825);
FORCEPROP 1 LAST VALUE 0.22UF
J 2
(-5925 925);
DISPLAY 0.617021 (-5925 925);
PAINT SKYBLUE (-5925 925);
FORCEPROP 0 LAST GROUP PCIE_UPLINK
J 0
(-6057 1120);
DISPLAY 0.638298 (-6057 1120);
PAINT BROWN (-6057 1120);
DISPLAY BOTH (-6057 1120);
FORCEPROP 2 LAST CDS_LOCATION C3P18
J 2
(-5925 975);
DISPLAY 0.617021 (-5925 975);
PAINT AQUA (-5925 975);
DISPLAY INVISIBLE (-5925 975);
FORCEPROP 1 LASTPIN (-5875 775) $PN 2
J 2
(-5885 755);
DISPLAY 0.787234 (-5885 755);
PAINT ORANGE (-5885 755);
DISPLAY INVISIBLE (-5885 755);
FORCEPROP 1 LASTPIN (-5875 975) $PN 1
J 2
(-5885 955);
DISPLAY 0.787234 (-5885 955);
PAINT ORANGE (-5885 955);
DISPLAY INVISIBLE (-5885 955);
FORCEPROP 2 LAST CDS_LIB mstr_discrete
J 0
(-5875 875);
PAINT ORANGE (-5875 875);
DISPLAY INVISIBLE (-5875 875);
FORCEPROP 1 LAST PATH I219
J 2
(-5925 1025);
DISPLAY 0.978723 (-5925 1025);
PAINT WHITE (-5925 1025);
DISPLAY INVISIBLE (-5925 1025);
FORCEPROP 2 LAST $SEC 1
J 0
(-5925 1075);
DISPLAY 0.680851 (-5925 1075);
PAINT MONO (-5925 1075);
DISPLAY INVISIBLE (-5925 1075);
FORCEPROP 2 LAST CDS_SEC 1
J 0
(-5925 1075);
DISPLAY 1.021277 (-5925 1075);
PAINT ORANGE (-5925 1075);
DISPLAY INVISIBLE (-5925 1075);
FORCEADD TAP..3
(-6075 1125);
FORCEPROP 3 LASTPIN (-6075 1075) SIG_NAME P3E_CPU0_PE1_SS_TXP<3>
J 0
(-6065 1085);
DISPLAY 0.659574 (-6065 1085);
PAINT MONO (-6065 1085);
DISPLAY INVISIBLE (-6065 1085);
FORCEPROP 1 LASTPIN (-6075 1075) BN 3
R 1
J 0
(-6082 1063);
DISPLAY 0.617021 (-6082 1063);
PAINT GREEN (-6082 1063);
FORCEPROP 1 LAST PATH I220
J 0
(-6077 1125);
DISPLAY 0.872340 (-6077 1125);
PAINT GREEN (-6077 1125);
DISPLAY INVISIBLE (-6077 1125);
FORCEPROP 2 LAST CDS_LIB mstr_standard
J 0
(-6075 1125);
PAINT ORANGE (-6075 1125);
DISPLAY INVISIBLE (-6075 1125);
FORCEPROP 1 LAST BODY_TYPE PLUMBING
J 0
(-6025 1075);
DISPLAY 2.276596 (-6025 1075);
PAINT GREEN (-6025 1075);
DISPLAY INVISIBLE (-6025 1075);
FORCEPROP 1 LAST HDL_TAP TRUE
J 0
(-5755 995);
DISPLAY 2.276596 (-5755 995);
PAINT GREEN (-5755 995);
DISPLAY INVISIBLE (-5755 995);
FORCEADD TAP..7
(-6125 1325);
FORCEPROP 3 LASTPIN (-6125 1375) SIG_NAME P3E_CPU0_PE1_PCH_TXN<3>
J 0
(-6115 1385);
DISPLAY 0.659574 (-6115 1385);
PAINT MONO (-6115 1385);
DISPLAY INVISIBLE (-6115 1385);
FORCEPROP 1 LASTPIN (-6125 1375) BN 3
R 1
J 0
(-6132 1323);
DISPLAY 0.617021 (-6132 1323);
PAINT GREEN (-6132 1323);
FORCEPROP 1 LAST PATH I221
J 0
(-6127 1325);
DISPLAY 0.872340 (-6127 1325);
PAINT GREEN (-6127 1325);
DISPLAY INVISIBLE (-6127 1325);
FORCEPROP 2 LAST CDS_LIB mstr_standard
J 0
(-6125 1325);
PAINT ORANGE (-6125 1325);
DISPLAY INVISIBLE (-6125 1325);
FORCEPROP 1 LAST BODY_TYPE PLUMBING
J 0
(-6075 1325);
DISPLAY 2.276596 (-6075 1325);
PAINT GREEN (-6075 1325);
DISPLAY INVISIBLE (-6075 1325);
FORCEPROP 1 LAST HDL_TAP TRUE
J 0
(-5805 1195);
DISPLAY 2.276596 (-5805 1195);
PAINT GREEN (-5805 1195);
DISPLAY INVISIBLE (-5805 1195);
FORCEADD TAP..3
(-6275 1125);
FORCEPROP 3 LASTPIN (-6275 1075) SIG_NAME P3E_CPU0_PE1_SS_TXP<4>
J 0
(-6265 1085);
DISPLAY 0.659574 (-6265 1085);
PAINT MONO (-6265 1085);
DISPLAY INVISIBLE (-6265 1085);
FORCEPROP 1 LASTPIN (-6275 1075) BN 4
R 1
J 0
(-6282 1063);
DISPLAY 0.617021 (-6282 1063);
PAINT GREEN (-6282 1063);
FORCEPROP 2 LAST CDS_LIB mstr_standard
J 0
(-6275 1125);
PAINT ORANGE (-6275 1125);
DISPLAY INVISIBLE (-6275 1125);
FORCEPROP 1 LAST PATH I222
J 0
(-6277 1125);
DISPLAY 0.872340 (-6277 1125);
PAINT GREEN (-6277 1125);
DISPLAY INVISIBLE (-6277 1125);
FORCEPROP 1 LAST BODY_TYPE PLUMBING
J 0
(-6225 1075);
DISPLAY 2.276596 (-6225 1075);
PAINT GREEN (-6225 1075);
DISPLAY INVISIBLE (-6225 1075);
FORCEPROP 1 LAST HDL_TAP TRUE
J 0
(-5955 995);
DISPLAY 2.276596 (-5955 995);
PAINT GREEN (-5955 995);
DISPLAY INVISIBLE (-5955 995);
FORCEADD CAP..1
R 2
(-6275 875);
FORCEPROP 1 LAST LOCATION C3P27
J 2
(-6325 975);
DISPLAY 0.617021 (-6325 975);
PAINT AQUA (-6325 975);
FORCEPROP 1 LAST VALUE 0.22UF
J 2
(-6325 925);
DISPLAY 0.617021 (-6325 925);
PAINT SKYBLUE (-6325 925);
FORCEPROP 1 LAST TOLERANCE 10%
J 2
(-6325 825);
DISPLAY 0.617021 (-6325 825);
PAINT SKYBLUE (-6325 825);
FORCEPROP 1 LAST VOLTAGE 16V
J 2
(-6325 875);
DISPLAY 0.617021 (-6325 875);
PAINT SKYBLUE (-6325 875);
FORCEPROP 1 LAST PACK_TYPE 0402
J 2
(-6325 675);
DISPLAY 0.617021 (-6325 675);
PAINT SKYBLUE (-6325 675);
FORCEPROP 1 LAST PART_NUMBER A36096-155
J 2
(-6325 725);
DISPLAY 0.617021 (-6325 725);
PAINT BLUE (-6325 725);
FORCEPROP 1 LAST MATERIAL X7R
J 2
(-6325 775);
DISPLAY 0.617021 (-6325 775);
PAINT SKYBLUE (-6325 775);
FORCEPROP 0 LAST GROUP PCIE_UPLINK
J 0
(-6457 1120);
DISPLAY 0.638298 (-6457 1120);
PAINT BROWN (-6457 1120);
DISPLAY BOTH (-6457 1120);
FORCEPROP 1 LASTPIN (-6275 775) $PN 2
J 2
(-6285 755);
DISPLAY 0.787234 (-6285 755);
PAINT ORANGE (-6285 755);
DISPLAY INVISIBLE (-6285 755);
FORCEPROP 1 LASTPIN (-6275 975) $PN 1
J 2
(-6285 955);
DISPLAY 0.787234 (-6285 955);
PAINT ORANGE (-6285 955);
DISPLAY INVISIBLE (-6285 955);
FORCEPROP 2 LAST CDS_LIB mstr_discrete
J 0
(-6275 875);
PAINT ORANGE (-6275 875);
DISPLAY INVISIBLE (-6275 875);
FORCEPROP 2 LAST CDS_LOCATION C3P27
J 2
(-6325 975);
DISPLAY 0.617021 (-6325 975);
PAINT AQUA (-6325 975);
DISPLAY INVISIBLE (-6325 975);
FORCEPROP 2 LAST CDS_SEC 1
J 0
(-6325 1075);
DISPLAY 1.021277 (-6325 1075);
PAINT ORANGE (-6325 1075);
DISPLAY INVISIBLE (-6325 1075);
FORCEPROP 2 LAST $SEC 1
J 0
(-6325 1075);
DISPLAY 0.680851 (-6325 1075);
PAINT MONO (-6325 1075);
DISPLAY INVISIBLE (-6325 1075);
FORCEPROP 1 LAST PATH I223
J 2
(-6325 1025);
DISPLAY 0.978723 (-6325 1025);
PAINT WHITE (-6325 1025);
DISPLAY INVISIBLE (-6325 1025);
FORCEADD TAP..7
(-5475 325);
FORCEPROP 3 LASTPIN (-5475 375) SIG_NAME P3E_CPU0_PE1_PCH_TXP<0>
J 0
(-5465 385);
DISPLAY 0.659574 (-5465 385);
PAINT MONO (-5465 385);
DISPLAY INVISIBLE (-5465 385);
FORCEPROP 1 LASTPIN (-5475 375) BN 0
R 1
J 0
(-5482 323);
DISPLAY 0.617021 (-5482 323);
PAINT GREEN (-5482 323);
FORCEPROP 2 LAST CDS_LIB mstr_standard
J 0
(-5475 325);
PAINT ORANGE (-5475 325);
DISPLAY INVISIBLE (-5475 325);
FORCEPROP 1 LAST PATH I224
J 0
(-5477 325);
DISPLAY 0.872340 (-5477 325);
PAINT GREEN (-5477 325);
DISPLAY INVISIBLE (-5477 325);
FORCEPROP 1 LAST BODY_TYPE PLUMBING
J 0
(-5425 325);
DISPLAY 2.276596 (-5425 325);
PAINT GREEN (-5425 325);
DISPLAY INVISIBLE (-5425 325);
FORCEPROP 1 LAST HDL_TAP TRUE
J 0
(-5155 195);
DISPLAY 2.276596 (-5155 195);
PAINT GREEN (-5155 195);
DISPLAY INVISIBLE (-5155 195);
FORCEADD OFFPAGE..2
(-5250 275);
FORCEPROP 2 LAST $XR0 117 
J 0
(-5061 275);
DISPLAY 0.638298 (-5061 275);
PAINT MONO (-5061 275);
FORCEPROP 2 LAST CDS_LIB mstr_standard
J 0
(-5250 275);
PAINT ORANGE (-5250 275);
DISPLAY INVISIBLE (-5250 275);
FORCEPROP 2 LAST PATH I225
J 0
(-5075 350);
DISPLAY 1.021277 (-5075 350);
PAINT ORANGE (-5075 350);
DISPLAY INVISIBLE (-5075 350);
FORCEPROP 1 LAST OFFPAGE TRUE
J 0
(-4925 150);
DISPLAY 0.872340 (-4925 150);
PAINT GREEN (-4925 150);
DISPLAY INVISIBLE (-4925 150);
FORCEPROP 1 LAST COMMENT_BODY TRUE
J 0
(-5295 180);
DISPLAY 0.872340 (-5295 180);
PAINT GREEN (-5295 180);
DISPLAY INVISIBLE (-5295 180);
FORCEADD CAP..1
R 2
(-5675 575);
FORCEPROP 1 LAST PART_NUMBER A36096-155
J 2
(-5725 425);
DISPLAY 0.617021 (-5725 425);
PAINT BLUE (-5725 425);
FORCEPROP 1 LAST PACK_TYPE 0402
J 2
(-5725 375);
DISPLAY 0.617021 (-5725 375);
PAINT SKYBLUE (-5725 375);
FORCEPROP 1 LAST MATERIAL X7R
J 2
(-5725 475);
DISPLAY 0.617021 (-5725 475);
PAINT SKYBLUE (-5725 475);
FORCEPROP 1 LAST VALUE 0.22UF
J 2
(-5725 625);
DISPLAY 0.617021 (-5725 625);
PAINT SKYBLUE (-5725 625);
FORCEPROP 1 LAST VOLTAGE 16V
J 2
(-5725 575);
DISPLAY 0.617021 (-5725 575);
PAINT SKYBLUE (-5725 575);
FORCEPROP 1 LAST TOLERANCE 10%
J 2
(-5725 525);
DISPLAY 0.617021 (-5725 525);
PAINT SKYBLUE (-5725 525);
FORCEPROP 1 LAST LOCATION C3P15
J 2
(-5725 675);
DISPLAY 0.617021 (-5725 675);
PAINT AQUA (-5725 675);
FORCEPROP 0 LAST GROUP PCIE_UPLINK
J 0
(-5857 295);
DISPLAY 0.638298 (-5857 295);
PAINT BROWN (-5857 295);
DISPLAY BOTH (-5857 295);
FORCEPROP 1 LASTPIN (-5675 475) $PN 2
J 2
(-5685 455);
DISPLAY 0.787234 (-5685 455);
PAINT ORANGE (-5685 455);
DISPLAY INVISIBLE (-5685 455);
FORCEPROP 1 LAST PATH I226
J 2
(-5725 725);
DISPLAY 0.978723 (-5725 725);
PAINT WHITE (-5725 725);
DISPLAY INVISIBLE (-5725 725);
FORCEPROP 1 LASTPIN (-5675 675) $PN 1
J 2
(-5685 655);
DISPLAY 0.787234 (-5685 655);
PAINT ORANGE (-5685 655);
DISPLAY INVISIBLE (-5685 655);
FORCEPROP 2 LAST CDS_LIB mstr_discrete
J 0
(-5675 575);
PAINT ORANGE (-5675 575);
DISPLAY INVISIBLE (-5675 575);
FORCEPROP 2 LAST CDS_LOCATION C3P15
J 2
(-5725 675);
DISPLAY 0.617021 (-5725 675);
PAINT AQUA (-5725 675);
DISPLAY INVISIBLE (-5725 675);
FORCEPROP 2 LAST $SEC 1
J 0
(-5725 775);
DISPLAY 0.680851 (-5725 775);
PAINT MONO (-5725 775);
DISPLAY INVISIBLE (-5725 775);
FORCEPROP 2 LAST CDS_SEC 1
J 0
(-5725 775);
DISPLAY 1.021277 (-5725 775);
PAINT ORANGE (-5725 775);
DISPLAY INVISIBLE (-5725 775);
FORCEADD TAP..7
(-5675 325);
FORCEPROP 3 LASTPIN (-5675 375) SIG_NAME P3E_CPU0_PE1_PCH_TXP<1>
J 0
(-5665 385);
DISPLAY 0.659574 (-5665 385);
PAINT MONO (-5665 385);
DISPLAY INVISIBLE (-5665 385);
FORCEPROP 1 LASTPIN (-5675 375) BN 1
R 1
J 0
(-5682 323);
DISPLAY 0.617021 (-5682 323);
PAINT GREEN (-5682 323);
FORCEPROP 1 LAST PATH I227
J 0
(-5677 325);
DISPLAY 0.872340 (-5677 325);
PAINT GREEN (-5677 325);
DISPLAY INVISIBLE (-5677 325);
FORCEPROP 2 LAST CDS_LIB mstr_standard
J 0
(-5675 325);
PAINT ORANGE (-5675 325);
DISPLAY INVISIBLE (-5675 325);
FORCEPROP 1 LAST BODY_TYPE PLUMBING
J 0
(-5625 325);
DISPLAY 2.276596 (-5625 325);
PAINT GREEN (-5625 325);
DISPLAY INVISIBLE (-5625 325);
FORCEPROP 1 LAST HDL_TAP TRUE
J 0
(-5355 195);
DISPLAY 2.276596 (-5355 195);
PAINT GREEN (-5355 195);
DISPLAY INVISIBLE (-5355 195);
FORCEADD TAP..7
(-5875 325);
FORCEPROP 3 LASTPIN (-5875 375) SIG_NAME P3E_CPU0_PE1_PCH_TXP<2>
J 0
(-5865 385);
DISPLAY 0.659574 (-5865 385);
PAINT MONO (-5865 385);
DISPLAY INVISIBLE (-5865 385);
FORCEPROP 1 LASTPIN (-5875 375) BN 2
R 1
J 0
(-5882 323);
DISPLAY 0.617021 (-5882 323);
PAINT GREEN (-5882 323);
FORCEPROP 1 LAST PATH I228
J 0
(-5877 325);
DISPLAY 0.872340 (-5877 325);
PAINT GREEN (-5877 325);
DISPLAY INVISIBLE (-5877 325);
FORCEPROP 2 LAST CDS_LIB mstr_standard
J 0
(-5875 325);
PAINT ORANGE (-5875 325);
DISPLAY INVISIBLE (-5875 325);
FORCEPROP 1 LAST BODY_TYPE PLUMBING
J 0
(-5825 325);
DISPLAY 2.276596 (-5825 325);
PAINT GREEN (-5825 325);
DISPLAY INVISIBLE (-5825 325);
FORCEPROP 1 LAST HDL_TAP TRUE
J 0
(-5555 195);
DISPLAY 2.276596 (-5555 195);
PAINT GREEN (-5555 195);
DISPLAY INVISIBLE (-5555 195);
FORCEADD CAP..1
R 2
(-6075 575);
FORCEPROP 1 LAST LOCATION C3P23
J 2
(-6125 675);
DISPLAY 0.617021 (-6125 675);
PAINT AQUA (-6125 675);
FORCEPROP 1 LAST PART_NUMBER A36096-155
J 2
(-6125 425);
DISPLAY 0.617021 (-6125 425);
PAINT BLUE (-6125 425);
FORCEPROP 1 LAST VALUE 0.22UF
J 2
(-6125 625);
DISPLAY 0.617021 (-6125 625);
PAINT SKYBLUE (-6125 625);
FORCEPROP 1 LAST TOLERANCE 10%
J 2
(-6125 525);
DISPLAY 0.617021 (-6125 525);
PAINT SKYBLUE (-6125 525);
FORCEPROP 1 LAST PACK_TYPE 0402
J 2
(-6125 375);
DISPLAY 0.617021 (-6125 375);
PAINT SKYBLUE (-6125 375);
FORCEPROP 1 LAST VOLTAGE 16V
J 2
(-6125 575);
DISPLAY 0.617021 (-6125 575);
PAINT SKYBLUE (-6125 575);
FORCEPROP 1 LAST MATERIAL X7R
J 2
(-6125 475);
DISPLAY 0.617021 (-6125 475);
PAINT SKYBLUE (-6125 475);
FORCEPROP 0 LAST GROUP PCIE_UPLINK
J 0
(-6257 295);
DISPLAY 0.638298 (-6257 295);
PAINT BROWN (-6257 295);
DISPLAY BOTH (-6257 295);
FORCEPROP 1 LASTPIN (-6075 475) $PN 2
J 2
(-6085 455);
DISPLAY 0.787234 (-6085 455);
PAINT ORANGE (-6085 455);
DISPLAY INVISIBLE (-6085 455);
FORCEPROP 1 LAST PATH I229
J 2
(-6125 725);
DISPLAY 0.978723 (-6125 725);
PAINT WHITE (-6125 725);
DISPLAY INVISIBLE (-6125 725);
FORCEPROP 2 LAST CDS_LOCATION C3P23
J 2
(-6125 675);
DISPLAY 0.617021 (-6125 675);
PAINT AQUA (-6125 675);
DISPLAY INVISIBLE (-6125 675);
FORCEPROP 2 LAST CDS_LIB mstr_discrete
J 0
(-6075 575);
PAINT ORANGE (-6075 575);
DISPLAY INVISIBLE (-6075 575);
FORCEPROP 1 LASTPIN (-6075 675) $PN 1
J 2
(-6085 655);
DISPLAY 0.787234 (-6085 655);
PAINT ORANGE (-6085 655);
DISPLAY INVISIBLE (-6085 655);
FORCEPROP 2 LAST $SEC 1
J 0
(-6125 775);
DISPLAY 0.680851 (-6125 775);
PAINT MONO (-6125 775);
DISPLAY INVISIBLE (-6125 775);
FORCEPROP 2 LAST CDS_SEC 1
J 0
(-6125 775);
DISPLAY 1.021277 (-6125 775);
PAINT ORANGE (-6125 775);
DISPLAY INVISIBLE (-6125 775);
FORCEADD TAP..7
(-6075 325);
FORCEPROP 3 LASTPIN (-6075 375) SIG_NAME P3E_CPU0_PE1_PCH_TXP<3>
J 0
(-6065 385);
DISPLAY 0.659574 (-6065 385);
PAINT MONO (-6065 385);
DISPLAY INVISIBLE (-6065 385);
FORCEPROP 1 LASTPIN (-6075 375) BN 3
R 1
J 0
(-6082 323);
DISPLAY 0.617021 (-6082 323);
PAINT GREEN (-6082 323);
FORCEPROP 1 LAST PATH I230
J 0
(-6077 325);
DISPLAY 0.872340 (-6077 325);
PAINT GREEN (-6077 325);
DISPLAY INVISIBLE (-6077 325);
FORCEPROP 2 LAST CDS_LIB mstr_standard
J 0
(-6075 325);
PAINT ORANGE (-6075 325);
DISPLAY INVISIBLE (-6075 325);
FORCEPROP 1 LAST BODY_TYPE PLUMBING
J 0
(-6025 325);
DISPLAY 2.276596 (-6025 325);
PAINT GREEN (-6025 325);
DISPLAY INVISIBLE (-6025 325);
FORCEPROP 1 LAST HDL_TAP TRUE
J 0
(-5755 195);
DISPLAY 2.276596 (-5755 195);
PAINT GREEN (-5755 195);
DISPLAY INVISIBLE (-5755 195);
FORCEADD TAP..7
(-6275 325);
FORCEPROP 3 LASTPIN (-6275 375) SIG_NAME P3E_CPU0_PE1_PCH_TXP<4>
J 0
(-6265 385);
DISPLAY 0.659574 (-6265 385);
PAINT MONO (-6265 385);
DISPLAY INVISIBLE (-6265 385);
FORCEPROP 1 LASTPIN (-6275 375) BN 4
R 1
J 0
(-6282 323);
DISPLAY 0.617021 (-6282 323);
PAINT GREEN (-6282 323);
FORCEPROP 2 LAST CDS_LIB mstr_standard
J 0
(-6275 325);
PAINT ORANGE (-6275 325);
DISPLAY INVISIBLE (-6275 325);
FORCEPROP 1 LAST PATH I231
J 0
(-6277 325);
DISPLAY 0.872340 (-6277 325);
PAINT GREEN (-6277 325);
DISPLAY INVISIBLE (-6277 325);
FORCEPROP 1 LAST BODY_TYPE PLUMBING
J 0
(-6225 325);
DISPLAY 2.276596 (-6225 325);
PAINT GREEN (-6225 325);
DISPLAY INVISIBLE (-6225 325);
FORCEPROP 1 LAST HDL_TAP TRUE
J 0
(-5955 195);
DISPLAY 2.276596 (-5955 195);
PAINT GREEN (-5955 195);
DISPLAY INVISIBLE (-5955 195);
FORCEADD CAP..1
R 2
(-6325 1875);
FORCEPROP 1 LAST TOLERANCE 10%
J 2
(-6375 1825);
DISPLAY 0.617021 (-6375 1825);
PAINT SKYBLUE (-6375 1825);
FORCEPROP 1 LAST VOLTAGE 16V
J 2
(-6375 1875);
DISPLAY 0.617021 (-6375 1875);
PAINT SKYBLUE (-6375 1875);
FORCEPROP 1 LAST MATERIAL X7R
J 2
(-6375 1775);
DISPLAY 0.617021 (-6375 1775);
PAINT SKYBLUE (-6375 1775);
FORCEPROP 1 LAST PART_NUMBER A36096-155
J 2
(-6375 1725);
DISPLAY 0.617021 (-6375 1725);
PAINT BLUE (-6375 1725);
FORCEPROP 1 LAST PACK_TYPE 0402
J 2
(-6375 1675);
DISPLAY 0.617021 (-6375 1675);
PAINT SKYBLUE (-6375 1675);
FORCEPROP 1 LAST VALUE 0.22UF
J 2
(-6375 1925);
DISPLAY 0.617021 (-6375 1925);
PAINT SKYBLUE (-6375 1925);
FORCEPROP 1 LAST LOCATION C3P28
J 2
(-6375 1975);
DISPLAY 0.617021 (-6375 1975);
PAINT AQUA (-6375 1975);
FORCEPROP 0 LAST GROUP PCIE_UPLINK
J 0
(-6507 2120);
DISPLAY 0.638298 (-6507 2120);
PAINT BROWN (-6507 2120);
DISPLAY BOTH (-6507 2120);
FORCEPROP 1 LASTPIN (-6325 1775) $PN 2
J 2
(-6335 1755);
DISPLAY 0.787234 (-6335 1755);
PAINT ORANGE (-6335 1755);
DISPLAY INVISIBLE (-6335 1755);
FORCEPROP 2 LAST CDS_LOCATION C3P28
J 2
(-6375 1975);
DISPLAY 0.617021 (-6375 1975);
PAINT AQUA (-6375 1975);
DISPLAY INVISIBLE (-6375 1975);
FORCEPROP 2 LAST CDS_LIB mstr_discrete
J 0
(-6325 1875);
PAINT ORANGE (-6325 1875);
DISPLAY INVISIBLE (-6325 1875);
FORCEPROP 1 LASTPIN (-6325 1975) $PN 1
J 2
(-6335 1955);
DISPLAY 0.787234 (-6335 1955);
PAINT ORANGE (-6335 1955);
DISPLAY INVISIBLE (-6335 1955);
FORCEPROP 1 LAST PATH I232
J 2
(-6375 2025);
DISPLAY 0.978723 (-6375 2025);
PAINT WHITE (-6375 2025);
DISPLAY INVISIBLE (-6375 2025);
FORCEPROP 2 LAST CDS_SEC 1
J 0
(-6375 2075);
DISPLAY 1.021277 (-6375 2075);
PAINT ORANGE (-6375 2075);
DISPLAY INVISIBLE (-6375 2075);
FORCEPROP 2 LAST $SEC 1
J 0
(-6375 2075);
DISPLAY 0.680851 (-6375 2075);
PAINT MONO (-6375 2075);
DISPLAY INVISIBLE (-6375 2075);
FORCEADD TAP..7
(-6325 1325);
FORCEPROP 3 LASTPIN (-6325 1375) SIG_NAME P3E_CPU0_PE1_PCH_TXN<4>
J 0
(-6315 1385);
DISPLAY 0.659574 (-6315 1385);
PAINT MONO (-6315 1385);
DISPLAY INVISIBLE (-6315 1385);
FORCEPROP 1 LASTPIN (-6325 1375) BN 4
R 1
J 0
(-6332 1323);
DISPLAY 0.617021 (-6332 1323);
PAINT GREEN (-6332 1323);
FORCEPROP 1 LAST PATH I233
J 0
(-6327 1325);
DISPLAY 0.872340 (-6327 1325);
PAINT GREEN (-6327 1325);
DISPLAY INVISIBLE (-6327 1325);
FORCEPROP 2 LAST CDS_LIB mstr_standard
J 0
(-6325 1325);
PAINT ORANGE (-6325 1325);
DISPLAY INVISIBLE (-6325 1325);
FORCEPROP 1 LAST BODY_TYPE PLUMBING
J 0
(-6275 1325);
DISPLAY 2.276596 (-6275 1325);
PAINT GREEN (-6275 1325);
DISPLAY INVISIBLE (-6275 1325);
FORCEPROP 1 LAST HDL_TAP TRUE
J 0
(-6005 1195);
DISPLAY 2.276596 (-6005 1195);
PAINT GREEN (-6005 1195);
DISPLAY INVISIBLE (-6005 1195);
FORCEADD CAP..1
R 2
(-6525 1575);
FORCEPROP 1 LAST MATERIAL X7R
J 2
(-6575 1475);
DISPLAY 0.617021 (-6575 1475);
PAINT SKYBLUE (-6575 1475);
FORCEPROP 1 LAST LOCATION C3P32
J 2
(-6575 1675);
DISPLAY 0.617021 (-6575 1675);
PAINT AQUA (-6575 1675);
FORCEPROP 1 LAST PACK_TYPE 0402
J 2
(-6575 1375);
DISPLAY 0.617021 (-6575 1375);
PAINT SKYBLUE (-6575 1375);
FORCEPROP 1 LAST TOLERANCE 10%
J 2
(-6575 1525);
DISPLAY 0.617021 (-6575 1525);
PAINT SKYBLUE (-6575 1525);
FORCEPROP 1 LAST PART_NUMBER A36096-155
J 2
(-6575 1425);
DISPLAY 0.617021 (-6575 1425);
PAINT BLUE (-6575 1425);
FORCEPROP 1 LAST VALUE 0.22UF
J 2
(-6575 1625);
DISPLAY 0.617021 (-6575 1625);
PAINT SKYBLUE (-6575 1625);
FORCEPROP 1 LAST VOLTAGE 16V
J 2
(-6575 1575);
DISPLAY 0.617021 (-6575 1575);
PAINT SKYBLUE (-6575 1575);
FORCEPROP 0 LAST GROUP PCIE_UPLINK
J 0
(-6707 1295);
DISPLAY 0.638298 (-6707 1295);
PAINT BROWN (-6707 1295);
DISPLAY BOTH (-6707 1295);
FORCEPROP 1 LASTPIN (-6525 1475) $PN 2
J 2
(-6535 1455);
DISPLAY 0.787234 (-6535 1455);
PAINT ORANGE (-6535 1455);
DISPLAY INVISIBLE (-6535 1455);
FORCEPROP 2 LAST $SEC 1
J 0
(-6575 1775);
DISPLAY 0.680851 (-6575 1775);
PAINT MONO (-6575 1775);
DISPLAY INVISIBLE (-6575 1775);
FORCEPROP 2 LAST CDS_SEC 1
J 0
(-6575 1775);
DISPLAY 1.021277 (-6575 1775);
PAINT ORANGE (-6575 1775);
DISPLAY INVISIBLE (-6575 1775);
FORCEPROP 2 LAST CDS_LIB mstr_discrete
J 0
(-6525 1575);
PAINT ORANGE (-6525 1575);
DISPLAY INVISIBLE (-6525 1575);
FORCEPROP 1 LAST PATH I234
J 2
(-6575 1725);
DISPLAY 0.978723 (-6575 1725);
PAINT WHITE (-6575 1725);
DISPLAY INVISIBLE (-6575 1725);
FORCEPROP 1 LASTPIN (-6525 1675) $PN 1
J 2
(-6535 1655);
DISPLAY 0.787234 (-6535 1655);
PAINT ORANGE (-6535 1655);
DISPLAY INVISIBLE (-6535 1655);
FORCEPROP 2 LAST CDS_LOCATION C3P32
J 2
(-6575 1675);
DISPLAY 0.617021 (-6575 1675);
PAINT AQUA (-6575 1675);
DISPLAY INVISIBLE (-6575 1675);
FORCEADD CAP..1
R 2
(-6725 1875);
FORCEPROP 1 LAST LOCATION C3P37
J 2
(-6775 1975);
DISPLAY 0.617021 (-6775 1975);
PAINT AQUA (-6775 1975);
FORCEPROP 1 LAST PART_NUMBER A36096-155
J 2
(-6775 1725);
DISPLAY 0.617021 (-6775 1725);
PAINT BLUE (-6775 1725);
FORCEPROP 1 LAST VALUE 0.22UF
J 2
(-6775 1925);
DISPLAY 0.617021 (-6775 1925);
PAINT SKYBLUE (-6775 1925);
FORCEPROP 1 LAST PACK_TYPE 0402
J 2
(-6775 1675);
DISPLAY 0.617021 (-6775 1675);
PAINT SKYBLUE (-6775 1675);
FORCEPROP 1 LAST MATERIAL X7R
J 2
(-6775 1775);
DISPLAY 0.617021 (-6775 1775);
PAINT SKYBLUE (-6775 1775);
FORCEPROP 1 LAST VOLTAGE 16V
J 2
(-6775 1875);
DISPLAY 0.617021 (-6775 1875);
PAINT SKYBLUE (-6775 1875);
FORCEPROP 1 LAST TOLERANCE 10%
J 2
(-6775 1825);
DISPLAY 0.617021 (-6775 1825);
PAINT SKYBLUE (-6775 1825);
FORCEPROP 0 LAST GROUP PCIE_UPLINK
J 0
(-6907 2120);
DISPLAY 0.638298 (-6907 2120);
PAINT BROWN (-6907 2120);
DISPLAY BOTH (-6907 2120);
FORCEPROP 1 LASTPIN (-6725 1775) $PN 2
J 2
(-6735 1755);
DISPLAY 0.787234 (-6735 1755);
PAINT ORANGE (-6735 1755);
DISPLAY INVISIBLE (-6735 1755);
FORCEPROP 2 LAST CDS_LOCATION C3P37
J 2
(-6775 1975);
DISPLAY 0.617021 (-6775 1975);
PAINT AQUA (-6775 1975);
DISPLAY INVISIBLE (-6775 1975);
FORCEPROP 2 LAST CDS_LIB mstr_discrete
J 0
(-6725 1875);
PAINT ORANGE (-6725 1875);
DISPLAY INVISIBLE (-6725 1875);
FORCEPROP 1 LASTPIN (-6725 1975) $PN 1
J 2
(-6735 1955);
DISPLAY 0.787234 (-6735 1955);
PAINT ORANGE (-6735 1955);
DISPLAY INVISIBLE (-6735 1955);
FORCEPROP 1 LAST PATH I235
J 2
(-6775 2025);
DISPLAY 0.978723 (-6775 2025);
PAINT WHITE (-6775 2025);
DISPLAY INVISIBLE (-6775 2025);
FORCEPROP 2 LAST CDS_SEC 1
J 0
(-6775 2075);
DISPLAY 1.021277 (-6775 2075);
PAINT ORANGE (-6775 2075);
DISPLAY INVISIBLE (-6775 2075);
FORCEPROP 2 LAST $SEC 1
J 0
(-6775 2075);
DISPLAY 0.680851 (-6775 2075);
PAINT MONO (-6775 2075);
DISPLAY INVISIBLE (-6775 2075);
FORCEADD TAP..7
(-6525 1325);
FORCEPROP 3 LASTPIN (-6525 1375) SIG_NAME P3E_CPU0_PE1_PCH_TXN<5>
J 0
(-6515 1385);
DISPLAY 0.659574 (-6515 1385);
PAINT MONO (-6515 1385);
DISPLAY INVISIBLE (-6515 1385);
FORCEPROP 1 LASTPIN (-6525 1375) BN 5
R 1
J 0
(-6532 1323);
DISPLAY 0.617021 (-6532 1323);
PAINT GREEN (-6532 1323);
FORCEPROP 2 LAST CDS_LIB mstr_standard
J 0
(-6525 1325);
PAINT ORANGE (-6525 1325);
DISPLAY INVISIBLE (-6525 1325);
FORCEPROP 1 LAST PATH I236
J 0
(-6527 1325);
DISPLAY 0.872340 (-6527 1325);
PAINT GREEN (-6527 1325);
DISPLAY INVISIBLE (-6527 1325);
FORCEPROP 1 LAST BODY_TYPE PLUMBING
J 0
(-6475 1325);
DISPLAY 2.276596 (-6475 1325);
PAINT GREEN (-6475 1325);
DISPLAY INVISIBLE (-6475 1325);
FORCEPROP 1 LAST HDL_TAP TRUE
J 0
(-6205 1195);
DISPLAY 2.276596 (-6205 1195);
PAINT GREEN (-6205 1195);
DISPLAY INVISIBLE (-6205 1195);
FORCEADD TAP..3
(-6475 1125);
FORCEPROP 3 LASTPIN (-6475 1075) SIG_NAME P3E_CPU0_PE1_SS_TXP<5>
J 0
(-6465 1085);
DISPLAY 0.659574 (-6465 1085);
PAINT MONO (-6465 1085);
DISPLAY INVISIBLE (-6465 1085);
FORCEPROP 1 LASTPIN (-6475 1075) BN 5
R 1
J 0
(-6482 1063);
DISPLAY 0.617021 (-6482 1063);
PAINT GREEN (-6482 1063);
FORCEPROP 1 LAST PATH I237
J 0
(-6477 1125);
DISPLAY 0.872340 (-6477 1125);
PAINT GREEN (-6477 1125);
DISPLAY INVISIBLE (-6477 1125);
FORCEPROP 2 LAST CDS_LIB mstr_standard
J 0
(-6475 1125);
PAINT ORANGE (-6475 1125);
DISPLAY INVISIBLE (-6475 1125);
FORCEPROP 1 LAST BODY_TYPE PLUMBING
J 0
(-6425 1075);
DISPLAY 2.276596 (-6425 1075);
PAINT GREEN (-6425 1075);
DISPLAY INVISIBLE (-6425 1075);
FORCEPROP 1 LAST HDL_TAP TRUE
J 0
(-6155 995);
DISPLAY 2.276596 (-6155 995);
PAINT GREEN (-6155 995);
DISPLAY INVISIBLE (-6155 995);
FORCEADD TAP..3
(-6675 1125);
FORCEPROP 3 LASTPIN (-6675 1075) SIG_NAME P3E_CPU0_PE1_SS_TXP<6>
J 0
(-6665 1085);
DISPLAY 0.659574 (-6665 1085);
PAINT MONO (-6665 1085);
DISPLAY INVISIBLE (-6665 1085);
FORCEPROP 1 LASTPIN (-6675 1075) BN 6
R 1
J 0
(-6682 1063);
DISPLAY 0.617021 (-6682 1063);
PAINT GREEN (-6682 1063);
FORCEPROP 1 LAST PATH I238
J 0
(-6677 1125);
DISPLAY 0.872340 (-6677 1125);
PAINT GREEN (-6677 1125);
DISPLAY INVISIBLE (-6677 1125);
FORCEPROP 2 LAST CDS_LIB mstr_standard
J 0
(-6675 1125);
PAINT ORANGE (-6675 1125);
DISPLAY INVISIBLE (-6675 1125);
FORCEPROP 1 LAST BODY_TYPE PLUMBING
J 0
(-6625 1075);
DISPLAY 2.276596 (-6625 1075);
PAINT GREEN (-6625 1075);
DISPLAY INVISIBLE (-6625 1075);
FORCEPROP 1 LAST HDL_TAP TRUE
J 0
(-6355 995);
DISPLAY 2.276596 (-6355 995);
PAINT GREEN (-6355 995);
DISPLAY INVISIBLE (-6355 995);
FORCEADD TAP..7
(-6725 1325);
FORCEPROP 3 LASTPIN (-6725 1375) SIG_NAME P3E_CPU0_PE1_PCH_TXN<6>
J 0
(-6715 1385);
DISPLAY 0.659574 (-6715 1385);
PAINT MONO (-6715 1385);
DISPLAY INVISIBLE (-6715 1385);
FORCEPROP 1 LASTPIN (-6725 1375) BN 6
R 1
J 0
(-6732 1323);
DISPLAY 0.617021 (-6732 1323);
PAINT GREEN (-6732 1323);
FORCEPROP 2 LAST CDS_LIB mstr_standard
J 0
(-6725 1325);
PAINT ORANGE (-6725 1325);
DISPLAY INVISIBLE (-6725 1325);
FORCEPROP 1 LAST PATH I239
J 0
(-6727 1325);
DISPLAY 0.872340 (-6727 1325);
PAINT GREEN (-6727 1325);
DISPLAY INVISIBLE (-6727 1325);
FORCEPROP 1 LAST BODY_TYPE PLUMBING
J 0
(-6675 1325);
DISPLAY 2.276596 (-6675 1325);
PAINT GREEN (-6675 1325);
DISPLAY INVISIBLE (-6675 1325);
FORCEPROP 1 LAST HDL_TAP TRUE
J 0
(-6405 1195);
DISPLAY 2.276596 (-6405 1195);
PAINT GREEN (-6405 1195);
DISPLAY INVISIBLE (-6405 1195);
FORCEADD CAP..1
R 2
(-6675 875);
FORCEPROP 1 LAST PART_NUMBER A36096-155
J 2
(-6725 725);
DISPLAY 0.617021 (-6725 725);
PAINT BLUE (-6725 725);
FORCEPROP 1 LAST PACK_TYPE 0402
J 2
(-6725 675);
DISPLAY 0.617021 (-6725 675);
PAINT SKYBLUE (-6725 675);
FORCEPROP 1 LAST MATERIAL X7R
J 2
(-6725 775);
DISPLAY 0.617021 (-6725 775);
PAINT SKYBLUE (-6725 775);
FORCEPROP 1 LAST VOLTAGE 16V
J 2
(-6725 875);
DISPLAY 0.617021 (-6725 875);
PAINT SKYBLUE (-6725 875);
FORCEPROP 1 LAST TOLERANCE 10%
J 2
(-6725 825);
DISPLAY 0.617021 (-6725 825);
PAINT SKYBLUE (-6725 825);
FORCEPROP 1 LAST VALUE 0.22UF
J 2
(-6725 925);
DISPLAY 0.617021 (-6725 925);
PAINT SKYBLUE (-6725 925);
FORCEPROP 1 LAST LOCATION C3P35
J 2
(-6725 975);
DISPLAY 0.617021 (-6725 975);
PAINT AQUA (-6725 975);
FORCEPROP 0 LAST GROUP PCIE_UPLINK
J 0
(-6857 1120);
DISPLAY 0.638298 (-6857 1120);
PAINT BROWN (-6857 1120);
DISPLAY BOTH (-6857 1120);
FORCEPROP 1 LASTPIN (-6675 775) $PN 2
J 2
(-6685 755);
DISPLAY 0.787234 (-6685 755);
PAINT ORANGE (-6685 755);
DISPLAY INVISIBLE (-6685 755);
FORCEPROP 1 LASTPIN (-6675 975) $PN 1
J 2
(-6685 955);
DISPLAY 0.787234 (-6685 955);
PAINT ORANGE (-6685 955);
DISPLAY INVISIBLE (-6685 955);
FORCEPROP 2 LAST CDS_LOCATION C3P35
J 2
(-6725 975);
DISPLAY 0.617021 (-6725 975);
PAINT AQUA (-6725 975);
DISPLAY INVISIBLE (-6725 975);
FORCEPROP 2 LAST CDS_LIB mstr_discrete
J 0
(-6675 875);
PAINT ORANGE (-6675 875);
DISPLAY INVISIBLE (-6675 875);
FORCEPROP 1 LAST PATH I240
J 2
(-6725 1025);
DISPLAY 0.978723 (-6725 1025);
PAINT WHITE (-6725 1025);
DISPLAY INVISIBLE (-6725 1025);
FORCEPROP 2 LAST $SEC 1
J 0
(-6725 1075);
DISPLAY 0.680851 (-6725 1075);
PAINT MONO (-6725 1075);
DISPLAY INVISIBLE (-6725 1075);
FORCEPROP 2 LAST CDS_SEC 1
J 0
(-6725 1075);
DISPLAY 1.021277 (-6725 1075);
PAINT ORANGE (-6725 1075);
DISPLAY INVISIBLE (-6725 1075);
FORCEADD CAP..1
R 2
(-6925 1575);
FORCEPROP 1 LAST PART_NUMBER A36096-155
J 2
(-6975 1425);
DISPLAY 0.617021 (-6975 1425);
PAINT BLUE (-6975 1425);
FORCEPROP 1 LAST PACK_TYPE 0402
J 2
(-6975 1375);
DISPLAY 0.617021 (-6975 1375);
PAINT SKYBLUE (-6975 1375);
FORCEPROP 1 LAST TOLERANCE 10%
J 2
(-6975 1525);
DISPLAY 0.617021 (-6975 1525);
PAINT SKYBLUE (-6975 1525);
FORCEPROP 1 LAST VOLTAGE 16V
J 2
(-6975 1575);
DISPLAY 0.617021 (-6975 1575);
PAINT SKYBLUE (-6975 1575);
FORCEPROP 1 LAST VALUE 0.22UF
J 2
(-6975 1625);
DISPLAY 0.617021 (-6975 1625);
PAINT SKYBLUE (-6975 1625);
FORCEPROP 1 LAST LOCATION C3P40
J 2
(-6975 1675);
DISPLAY 0.617021 (-6975 1675);
PAINT AQUA (-6975 1675);
FORCEPROP 1 LAST MATERIAL X7R
J 2
(-6975 1475);
DISPLAY 0.617021 (-6975 1475);
PAINT SKYBLUE (-6975 1475);
FORCEPROP 0 LAST GROUP PCIE_UPLINK
J 0
(-7182 1295);
DISPLAY 0.638298 (-7182 1295);
PAINT BROWN (-7182 1295);
DISPLAY BOTH (-7182 1295);
FORCEPROP 1 LASTPIN (-6925 1475) $PN 2
J 2
(-6935 1455);
DISPLAY 0.787234 (-6935 1455);
PAINT ORANGE (-6935 1455);
DISPLAY INVISIBLE (-6935 1455);
FORCEPROP 2 LAST CDS_LOCATION C3P40
J 2
(-6975 1675);
DISPLAY 0.617021 (-6975 1675);
PAINT AQUA (-6975 1675);
DISPLAY INVISIBLE (-6975 1675);
FORCEPROP 1 LASTPIN (-6925 1675) $PN 1
J 2
(-6935 1655);
DISPLAY 0.787234 (-6935 1655);
PAINT ORANGE (-6935 1655);
DISPLAY INVISIBLE (-6935 1655);
FORCEPROP 2 LAST $SEC 1
J 0
(-6975 1775);
DISPLAY 0.680851 (-6975 1775);
PAINT MONO (-6975 1775);
DISPLAY INVISIBLE (-6975 1775);
FORCEPROP 2 LAST CDS_LIB mstr_discrete
J 0
(-6925 1575);
PAINT ORANGE (-6925 1575);
DISPLAY INVISIBLE (-6925 1575);
FORCEPROP 2 LAST CDS_SEC 1
J 0
(-6975 1775);
DISPLAY 1.021277 (-6975 1775);
PAINT ORANGE (-6975 1775);
DISPLAY INVISIBLE (-6975 1775);
FORCEPROP 1 LAST PATH I241
J 2
(-6975 1725);
DISPLAY 0.978723 (-6975 1725);
PAINT WHITE (-6975 1725);
DISPLAY INVISIBLE (-6975 1725);
FORCEADD TAP..7
(-6925 1325);
FORCEPROP 3 LASTPIN (-6925 1375) SIG_NAME P3E_CPU0_PE1_PCH_TXN<7>
J 0
(-6915 1385);
DISPLAY 0.659574 (-6915 1385);
PAINT MONO (-6915 1385);
DISPLAY INVISIBLE (-6915 1385);
FORCEPROP 1 LASTPIN (-6925 1375) BN 7
R 1
J 0
(-6932 1323);
DISPLAY 0.617021 (-6932 1323);
PAINT GREEN (-6932 1323);
FORCEPROP 2 LAST CDS_LIB mstr_standard
J 0
(-6925 1325);
PAINT ORANGE (-6925 1325);
DISPLAY INVISIBLE (-6925 1325);
FORCEPROP 1 LAST PATH I242
J 0
(-6927 1325);
DISPLAY 0.872340 (-6927 1325);
PAINT GREEN (-6927 1325);
DISPLAY INVISIBLE (-6927 1325);
FORCEPROP 1 LAST BODY_TYPE PLUMBING
J 0
(-6875 1325);
DISPLAY 2.276596 (-6875 1325);
PAINT GREEN (-6875 1325);
DISPLAY INVISIBLE (-6875 1325);
FORCEPROP 1 LAST HDL_TAP TRUE
J 0
(-6605 1195);
DISPLAY 2.276596 (-6605 1195);
PAINT GREEN (-6605 1195);
DISPLAY INVISIBLE (-6605 1195);
FORCEADD TAP..3
(-6875 1125);
FORCEPROP 3 LASTPIN (-6875 1075) SIG_NAME P3E_CPU0_PE1_SS_TXP<7>
J 0
(-6865 1085);
DISPLAY 0.659574 (-6865 1085);
PAINT MONO (-6865 1085);
DISPLAY INVISIBLE (-6865 1085);
FORCEPROP 1 LASTPIN (-6875 1075) BN 7
R 1
J 0
(-6882 1063);
DISPLAY 0.617021 (-6882 1063);
PAINT GREEN (-6882 1063);
FORCEPROP 2 LAST CDS_LIB mstr_standard
J 0
(-6875 1125);
PAINT ORANGE (-6875 1125);
DISPLAY INVISIBLE (-6875 1125);
FORCEPROP 1 LAST PATH I243
J 0
(-6877 1125);
DISPLAY 0.872340 (-6877 1125);
PAINT GREEN (-6877 1125);
DISPLAY INVISIBLE (-6877 1125);
FORCEPROP 1 LAST BODY_TYPE PLUMBING
J 0
(-6825 1075);
DISPLAY 2.276596 (-6825 1075);
PAINT GREEN (-6825 1075);
DISPLAY INVISIBLE (-6825 1075);
FORCEPROP 1 LAST HDL_TAP TRUE
J 0
(-6555 995);
DISPLAY 2.276596 (-6555 995);
PAINT GREEN (-6555 995);
DISPLAY INVISIBLE (-6555 995);
FORCEADD OFFPAGE..1
(-7050 1175);
FORCEPROP 2 LAST $XR1 107 
J 0
(-7391 1175);
DISPLAY 0.638298 (-7391 1175);
PAINT MONO (-7391 1175);
FORCEPROP 2 LAST $XR0 30 
J 0
(-7271 1175);
DISPLAY 0.638298 (-7271 1175);
PAINT MONO (-7271 1175);
FORCEPROP 2 LAST CDS_LIB mstr_standard
J 0
(-7050 1175);
PAINT ORANGE (-7050 1175);
DISPLAY INVISIBLE (-7050 1175);
FORCEPROP 2 LAST PATH I244
J 0
(-7000 1250);
DISPLAY 1.021277 (-7000 1250);
PAINT ORANGE (-7000 1250);
DISPLAY INVISIBLE (-7000 1250);
FORCEPROP 1 LAST OFFPAGE TRUE
J 0
(-6730 1045);
PAINT GREEN (-6730 1045);
DISPLAY INVISIBLE (-6730 1045);
FORCEPROP 1 LAST COMMENT_BODY TRUE
J 0
(-6930 1075);
DISPLAY 2.276596 (-6930 1075);
PAINT GREEN (-6930 1075);
DISPLAY INVISIBLE (-6930 1075);
FORCEADD CAP..1
R 2
(-6475 575);
FORCEPROP 1 LAST LOCATION C3P30
J 2
(-6525 675);
DISPLAY 0.617021 (-6525 675);
PAINT AQUA (-6525 675);
FORCEPROP 1 LAST PART_NUMBER A36096-155
J 2
(-6525 425);
DISPLAY 0.617021 (-6525 425);
PAINT BLUE (-6525 425);
FORCEPROP 1 LAST VALUE 0.22UF
J 2
(-6525 625);
DISPLAY 0.617021 (-6525 625);
PAINT SKYBLUE (-6525 625);
FORCEPROP 1 LAST MATERIAL X7R
J 2
(-6525 475);
DISPLAY 0.617021 (-6525 475);
PAINT SKYBLUE (-6525 475);
FORCEPROP 1 LAST PACK_TYPE 0402
J 2
(-6525 375);
DISPLAY 0.617021 (-6525 375);
PAINT SKYBLUE (-6525 375);
FORCEPROP 1 LAST VOLTAGE 16V
J 2
(-6525 575);
DISPLAY 0.617021 (-6525 575);
PAINT SKYBLUE (-6525 575);
FORCEPROP 1 LAST TOLERANCE 10%
J 2
(-6525 525);
DISPLAY 0.617021 (-6525 525);
PAINT SKYBLUE (-6525 525);
FORCEPROP 0 LAST GROUP PCIE_UPLINK
J 0
(-6657 295);
DISPLAY 0.638298 (-6657 295);
PAINT BROWN (-6657 295);
DISPLAY BOTH (-6657 295);
FORCEPROP 1 LASTPIN (-6475 475) $PN 2
J 2
(-6485 455);
DISPLAY 0.787234 (-6485 455);
PAINT ORANGE (-6485 455);
DISPLAY INVISIBLE (-6485 455);
FORCEPROP 2 LAST CDS_LIB mstr_discrete
J 0
(-6475 575);
PAINT ORANGE (-6475 575);
DISPLAY INVISIBLE (-6475 575);
FORCEPROP 2 LAST $SEC 1
J 0
(-6525 775);
DISPLAY 0.680851 (-6525 775);
PAINT MONO (-6525 775);
DISPLAY INVISIBLE (-6525 775);
FORCEPROP 1 LASTPIN (-6475 675) $PN 1
J 2
(-6485 655);
DISPLAY 0.787234 (-6485 655);
PAINT ORANGE (-6485 655);
DISPLAY INVISIBLE (-6485 655);
FORCEPROP 2 LAST CDS_SEC 1
J 0
(-6525 775);
DISPLAY 1.021277 (-6525 775);
PAINT ORANGE (-6525 775);
DISPLAY INVISIBLE (-6525 775);
FORCEPROP 1 LAST PATH I245
J 2
(-6525 725);
DISPLAY 0.978723 (-6525 725);
PAINT WHITE (-6525 725);
DISPLAY INVISIBLE (-6525 725);
FORCEPROP 2 LAST CDS_LOCATION C3P30
J 2
(-6525 675);
DISPLAY 0.617021 (-6525 675);
PAINT AQUA (-6525 675);
DISPLAY INVISIBLE (-6525 675);
FORCEADD TAP..7
(-6475 325);
FORCEPROP 3 LASTPIN (-6475 375) SIG_NAME P3E_CPU0_PE1_PCH_TXP<5>
J 0
(-6465 385);
DISPLAY 0.659574 (-6465 385);
PAINT MONO (-6465 385);
DISPLAY INVISIBLE (-6465 385);
FORCEPROP 1 LASTPIN (-6475 375) BN 5
R 1
J 0
(-6482 323);
DISPLAY 0.617021 (-6482 323);
PAINT GREEN (-6482 323);
FORCEPROP 1 LAST PATH I246
J 0
(-6477 325);
DISPLAY 0.872340 (-6477 325);
PAINT GREEN (-6477 325);
DISPLAY INVISIBLE (-6477 325);
FORCEPROP 2 LAST CDS_LIB mstr_standard
J 0
(-6475 325);
PAINT ORANGE (-6475 325);
DISPLAY INVISIBLE (-6475 325);
FORCEPROP 1 LAST BODY_TYPE PLUMBING
J 0
(-6425 325);
DISPLAY 2.276596 (-6425 325);
PAINT GREEN (-6425 325);
DISPLAY INVISIBLE (-6425 325);
FORCEPROP 1 LAST HDL_TAP TRUE
J 0
(-6155 195);
DISPLAY 2.276596 (-6155 195);
PAINT GREEN (-6155 195);
DISPLAY INVISIBLE (-6155 195);
FORCEADD TAP..7
(-6675 325);
FORCEPROP 3 LASTPIN (-6675 375) SIG_NAME P3E_CPU0_PE1_PCH_TXP<6>
J 0
(-6665 385);
DISPLAY 0.659574 (-6665 385);
PAINT MONO (-6665 385);
DISPLAY INVISIBLE (-6665 385);
FORCEPROP 1 LASTPIN (-6675 375) BN 6
R 1
J 0
(-6682 323);
DISPLAY 0.617021 (-6682 323);
PAINT GREEN (-6682 323);
FORCEPROP 2 LAST CDS_LIB mstr_standard
J 0
(-6675 325);
PAINT ORANGE (-6675 325);
DISPLAY INVISIBLE (-6675 325);
FORCEPROP 1 LAST PATH I247
J 0
(-6677 325);
DISPLAY 0.872340 (-6677 325);
PAINT GREEN (-6677 325);
DISPLAY INVISIBLE (-6677 325);
FORCEPROP 1 LAST BODY_TYPE PLUMBING
J 0
(-6625 325);
DISPLAY 2.276596 (-6625 325);
PAINT GREEN (-6625 325);
DISPLAY INVISIBLE (-6625 325);
FORCEPROP 1 LAST HDL_TAP TRUE
J 0
(-6355 195);
DISPLAY 2.276596 (-6355 195);
PAINT GREEN (-6355 195);
DISPLAY INVISIBLE (-6355 195);
FORCEADD CAP..1
R 2
(-6875 575);
FORCEPROP 1 LAST PART_NUMBER A36096-155
J 2
(-6925 425);
DISPLAY 0.617021 (-6925 425);
PAINT BLUE (-6925 425);
FORCEPROP 1 LAST MATERIAL X7R
J 2
(-6925 475);
DISPLAY 0.617021 (-6925 475);
PAINT SKYBLUE (-6925 475);
FORCEPROP 1 LAST PACK_TYPE 0402
J 2
(-6925 375);
DISPLAY 0.617021 (-6925 375);
PAINT SKYBLUE (-6925 375);
FORCEPROP 1 LAST VOLTAGE 16V
J 2
(-6925 575);
DISPLAY 0.617021 (-6925 575);
PAINT SKYBLUE (-6925 575);
FORCEPROP 1 LAST TOLERANCE 10%
J 2
(-6925 525);
DISPLAY 0.617021 (-6925 525);
PAINT SKYBLUE (-6925 525);
FORCEPROP 1 LAST VALUE 0.22UF
J 2
(-6925 625);
DISPLAY 0.617021 (-6925 625);
PAINT SKYBLUE (-6925 625);
FORCEPROP 1 LAST LOCATION C3P39
J 2
(-6925 675);
DISPLAY 0.617021 (-6925 675);
PAINT AQUA (-6925 675);
FORCEPROP 0 LAST GROUP PCIE_UPLINK
J 0
(-7107 270);
DISPLAY 0.638298 (-7107 270);
PAINT BROWN (-7107 270);
DISPLAY BOTH (-7107 270);
FORCEPROP 1 LASTPIN (-6875 475) $PN 2
J 2
(-6885 455);
DISPLAY 0.787234 (-6885 455);
PAINT ORANGE (-6885 455);
DISPLAY INVISIBLE (-6885 455);
FORCEPROP 1 LAST PATH I248
J 2
(-6925 725);
DISPLAY 0.978723 (-6925 725);
PAINT WHITE (-6925 725);
DISPLAY INVISIBLE (-6925 725);
FORCEPROP 2 LAST CDS_LOCATION C3P39
J 2
(-6925 675);
DISPLAY 0.617021 (-6925 675);
PAINT AQUA (-6925 675);
DISPLAY INVISIBLE (-6925 675);
FORCEPROP 2 LAST CDS_SEC 1
J 0
(-6925 775);
DISPLAY 1.021277 (-6925 775);
PAINT ORANGE (-6925 775);
DISPLAY INVISIBLE (-6925 775);
FORCEPROP 2 LAST $SEC 1
J 0
(-6925 775);
DISPLAY 0.680851 (-6925 775);
PAINT MONO (-6925 775);
DISPLAY INVISIBLE (-6925 775);
FORCEPROP 1 LASTPIN (-6875 675) $PN 1
J 2
(-6885 655);
DISPLAY 0.787234 (-6885 655);
PAINT ORANGE (-6885 655);
DISPLAY INVISIBLE (-6885 655);
FORCEPROP 2 LAST CDS_LIB mstr_discrete
J 0
(-6875 575);
PAINT ORANGE (-6875 575);
DISPLAY INVISIBLE (-6875 575);
FORCEADD TAP..7
(-6875 325);
FORCEPROP 3 LASTPIN (-6875 375) SIG_NAME P3E_CPU0_PE1_PCH_TXP<7>
J 0
(-6865 385);
DISPLAY 0.659574 (-6865 385);
PAINT MONO (-6865 385);
DISPLAY INVISIBLE (-6865 385);
FORCEPROP 1 LASTPIN (-6875 375) BN 7
R 1
J 0
(-6882 323);
DISPLAY 0.617021 (-6882 323);
PAINT GREEN (-6882 323);
FORCEPROP 2 LAST CDS_LIB mstr_standard
J 0
(-6875 325);
PAINT ORANGE (-6875 325);
DISPLAY INVISIBLE (-6875 325);
FORCEPROP 1 LAST PATH I249
J 0
(-6877 325);
DISPLAY 0.872340 (-6877 325);
PAINT GREEN (-6877 325);
DISPLAY INVISIBLE (-6877 325);
FORCEPROP 1 LAST BODY_TYPE PLUMBING
J 0
(-6825 325);
DISPLAY 2.276596 (-6825 325);
PAINT GREEN (-6825 325);
DISPLAY INVISIBLE (-6825 325);
FORCEPROP 1 LAST HDL_TAP TRUE
J 0
(-6555 195);
DISPLAY 2.276596 (-6555 195);
PAINT GREEN (-6555 195);
DISPLAY INVISIBLE (-6555 195);
FORCEADD TAP..3
(-1950 2075);
FORCEPROP 3 LASTPIN (-1950 2025) SIG_NAME P3E_CPU0_PE1_PCH_RXN<0>
J 0
(-1940 2035);
DISPLAY 0.659574 (-1940 2035);
PAINT MONO (-1940 2035);
DISPLAY INVISIBLE (-1940 2035);
FORCEPROP 1 LASTPIN (-1950 2025) BN 0
R 1
J 0
(-1957 2013);
DISPLAY 0.617021 (-1957 2013);
PAINT GREEN (-1957 2013);
FORCEPROP 2 LAST CDS_LIB mstr_standard
J 0
(-1950 2075);
PAINT ORANGE (-1950 2075);
DISPLAY INVISIBLE (-1950 2075);
FORCEPROP 1 LAST PATH I250
J 0
(-1952 2075);
DISPLAY 0.872340 (-1952 2075);
PAINT GREEN (-1952 2075);
DISPLAY INVISIBLE (-1952 2075);
FORCEPROP 1 LAST BODY_TYPE PLUMBING
J 0
(-1900 2025);
DISPLAY 2.276596 (-1900 2025);
PAINT GREEN (-1900 2025);
DISPLAY INVISIBLE (-1900 2025);
FORCEPROP 1 LAST HDL_TAP TRUE
J 0
(-1630 1945);
DISPLAY 2.276596 (-1630 1945);
PAINT GREEN (-1630 1945);
DISPLAY INVISIBLE (-1630 1945);
FORCEADD TAP..3
(-2150 2075);
FORCEPROP 3 LASTPIN (-2150 2025) SIG_NAME P3E_CPU0_PE1_PCH_RXN<1>
J 0
(-2140 2035);
DISPLAY 0.659574 (-2140 2035);
PAINT MONO (-2140 2035);
DISPLAY INVISIBLE (-2140 2035);
FORCEPROP 1 LASTPIN (-2150 2025) BN 1
R 1
J 0
(-2157 2013);
DISPLAY 0.617021 (-2157 2013);
PAINT GREEN (-2157 2013);
FORCEPROP 2 LAST CDS_LIB mstr_standard
J 0
(-2150 2075);
PAINT ORANGE (-2150 2075);
DISPLAY INVISIBLE (-2150 2075);
FORCEPROP 1 LAST PATH I251
J 0
(-2152 2075);
DISPLAY 0.872340 (-2152 2075);
PAINT GREEN (-2152 2075);
DISPLAY INVISIBLE (-2152 2075);
FORCEPROP 1 LAST BODY_TYPE PLUMBING
J 0
(-2100 2025);
DISPLAY 2.276596 (-2100 2025);
PAINT GREEN (-2100 2025);
DISPLAY INVISIBLE (-2100 2025);
FORCEPROP 1 LAST HDL_TAP TRUE
J 0
(-1830 1945);
DISPLAY 2.276596 (-1830 1945);
PAINT GREEN (-1830 1945);
DISPLAY INVISIBLE (-1830 1945);
FORCEADD TAP..3
(-2350 2075);
FORCEPROP 3 LASTPIN (-2350 2025) SIG_NAME P3E_CPU0_PE1_PCH_RXN<2>
J 0
(-2340 2035);
DISPLAY 0.659574 (-2340 2035);
PAINT MONO (-2340 2035);
DISPLAY INVISIBLE (-2340 2035);
FORCEPROP 1 LASTPIN (-2350 2025) BN 2
R 1
J 0
(-2357 2013);
DISPLAY 0.617021 (-2357 2013);
PAINT GREEN (-2357 2013);
FORCEPROP 1 LAST PATH I252
J 0
(-2352 2075);
DISPLAY 0.872340 (-2352 2075);
PAINT GREEN (-2352 2075);
DISPLAY INVISIBLE (-2352 2075);
FORCEPROP 2 LAST CDS_LIB mstr_standard
J 0
(-2350 2075);
PAINT ORANGE (-2350 2075);
DISPLAY INVISIBLE (-2350 2075);
FORCEPROP 1 LAST BODY_TYPE PLUMBING
J 0
(-2300 2025);
DISPLAY 2.276596 (-2300 2025);
PAINT GREEN (-2300 2025);
DISPLAY INVISIBLE (-2300 2025);
FORCEPROP 1 LAST HDL_TAP TRUE
J 0
(-2030 1945);
DISPLAY 2.276596 (-2030 1945);
PAINT GREEN (-2030 1945);
DISPLAY INVISIBLE (-2030 1945);
FORCEADD TAP..3
(-2550 2075);
FORCEPROP 3 LASTPIN (-2550 2025) SIG_NAME P3E_CPU0_PE1_PCH_RXN<3>
J 0
(-2540 2035);
DISPLAY 0.659574 (-2540 2035);
PAINT MONO (-2540 2035);
DISPLAY INVISIBLE (-2540 2035);
FORCEPROP 1 LASTPIN (-2550 2025) BN 3
R 1
J 0
(-2557 2013);
DISPLAY 0.617021 (-2557 2013);
PAINT GREEN (-2557 2013);
FORCEPROP 1 LAST PATH I253
J 0
(-2552 2075);
DISPLAY 0.872340 (-2552 2075);
PAINT GREEN (-2552 2075);
DISPLAY INVISIBLE (-2552 2075);
FORCEPROP 2 LAST CDS_LIB mstr_standard
J 0
(-2550 2075);
PAINT ORANGE (-2550 2075);
DISPLAY INVISIBLE (-2550 2075);
FORCEPROP 1 LAST BODY_TYPE PLUMBING
J 0
(-2500 2025);
DISPLAY 2.276596 (-2500 2025);
PAINT GREEN (-2500 2025);
DISPLAY INVISIBLE (-2500 2025);
FORCEPROP 1 LAST HDL_TAP TRUE
J 0
(-2230 1945);
DISPLAY 2.276596 (-2230 1945);
PAINT GREEN (-2230 1945);
DISPLAY INVISIBLE (-2230 1945);
FORCEADD TAP..3
(-2750 2075);
FORCEPROP 3 LASTPIN (-2750 2025) SIG_NAME P3E_CPU0_PE1_PCH_RXN<4>
J 0
(-2740 2035);
DISPLAY 0.659574 (-2740 2035);
PAINT MONO (-2740 2035);
DISPLAY INVISIBLE (-2740 2035);
FORCEPROP 1 LASTPIN (-2750 2025) BN 4
R 1
J 0
(-2757 2013);
DISPLAY 0.617021 (-2757 2013);
PAINT GREEN (-2757 2013);
FORCEPROP 2 LAST CDS_LIB mstr_standard
J 0
(-2750 2075);
PAINT ORANGE (-2750 2075);
DISPLAY INVISIBLE (-2750 2075);
FORCEPROP 1 LAST PATH I254
J 0
(-2752 2075);
DISPLAY 0.872340 (-2752 2075);
PAINT GREEN (-2752 2075);
DISPLAY INVISIBLE (-2752 2075);
FORCEPROP 1 LAST BODY_TYPE PLUMBING
J 0
(-2700 2025);
DISPLAY 2.276596 (-2700 2025);
PAINT GREEN (-2700 2025);
DISPLAY INVISIBLE (-2700 2025);
FORCEPROP 1 LAST HDL_TAP TRUE
J 0
(-2430 1945);
DISPLAY 2.276596 (-2430 1945);
PAINT GREEN (-2430 1945);
DISPLAY INVISIBLE (-2430 1945);
FORCEADD OFFPAGE..2
(-1700 1225);
FORCEPROP 2 LAST $XR1 30 
J 0
(-1391 1225);
DISPLAY 0.638298 (-1391 1225);
PAINT MONO (-1391 1225);
FORCEPROP 2 LAST $XR0 107 
J 0
(-1511 1225);
DISPLAY 0.638298 (-1511 1225);
PAINT MONO (-1511 1225);
FORCEPROP 2 LAST CDS_LIB mstr_standard
J 0
(-1700 1225);
PAINT ORANGE (-1700 1225);
DISPLAY INVISIBLE (-1700 1225);
FORCEPROP 2 LAST PATH I255
J 0
(-1525 1300);
DISPLAY 1.021277 (-1525 1300);
PAINT ORANGE (-1525 1300);
DISPLAY INVISIBLE (-1525 1300);
FORCEPROP 1 LAST OFFPAGE TRUE
J 0
(-1375 1100);
DISPLAY 0.872340 (-1375 1100);
PAINT GREEN (-1375 1100);
DISPLAY INVISIBLE (-1375 1100);
FORCEPROP 1 LAST COMMENT_BODY TRUE
J 0
(-1745 1130);
DISPLAY 0.872340 (-1745 1130);
PAINT GREEN (-1745 1130);
DISPLAY INVISIBLE (-1745 1130);
FORCEADD OFFPAGE..2
(-1675 225);
FORCEPROP 2 LAST $XR1 30 
J 0
(-1366 225);
DISPLAY 0.638298 (-1366 225);
PAINT MONO (-1366 225);
FORCEPROP 2 LAST $XR0 107 
J 0
(-1486 225);
DISPLAY 0.638298 (-1486 225);
PAINT MONO (-1486 225);
FORCEPROP 2 LAST CDS_LIB mstr_standard
J 0
(-1675 225);
PAINT ORANGE (-1675 225);
DISPLAY INVISIBLE (-1675 225);
FORCEPROP 2 LAST PATH I256
J 0
(-1500 300);
DISPLAY 1.021277 (-1500 300);
PAINT ORANGE (-1500 300);
DISPLAY INVISIBLE (-1500 300);
FORCEPROP 1 LAST OFFPAGE TRUE
J 0
(-1350 100);
DISPLAY 0.872340 (-1350 100);
PAINT GREEN (-1350 100);
DISPLAY INVISIBLE (-1350 100);
FORCEPROP 1 LAST COMMENT_BODY TRUE
J 0
(-1720 130);
DISPLAY 0.872340 (-1720 130);
PAINT GREEN (-1720 130);
DISPLAY INVISIBLE (-1720 130);
FORCEADD CAP..1
R 2
(-1950 1875);
FORCEPROP 0 LAST GROUP PCIE_UPLINK
J 0
(-2107 2070);
DISPLAY 0.638298 (-2107 2070);
PAINT BROWN (-2107 2070);
DISPLAY BOTH (-2107 2070);
FORCEPROP 1 LAST PART_NUMBER A36096-155
R 1
J 2
(-1875 2000);
DISPLAY 0.617021 (-1875 2000);
PAINT BLUE (-1875 2000);
FORCEPROP 1 LAST LOCATION C2U4
J 2
(-2000 1975);
DISPLAY 0.617021 (-2000 1975);
PAINT AQUA (-2000 1975);
FORCEPROP 1 LASTPIN (-1950 1975) $PN 1
J 2
(-1955 1937);
DISPLAY 0.617021 (-1955 1937);
PAINT ORANGE (-1955 1937);
FORCEPROP 1 LAST VALUE 0.22UF
J 2
(-2000 1925);
DISPLAY 0.617021 (-2000 1925);
PAINT SKYBLUE (-2000 1925);
FORCEPROP 1 LAST VOLTAGE 16V
J 2
(-2000 1875);
DISPLAY 0.617021 (-2000 1875);
PAINT SKYBLUE (-2000 1875);
FORCEPROP 1 LAST TOLERANCE 10%
J 2
(-2000 1825);
DISPLAY 0.617021 (-2000 1825);
PAINT SKYBLUE (-2000 1825);
FORCEPROP 1 LASTPIN (-1950 1775) $PN 2
J 2
(-1955 1785);
DISPLAY 0.617021 (-1955 1785);
PAINT ORANGE (-1955 1785);
FORCEPROP 1 LAST MATERIAL X7R
J 2
(-2000 1775);
DISPLAY 0.617021 (-2000 1775);
PAINT SKYBLUE (-2000 1775);
FORCEPROP 1 LAST PACK_TYPE 0402
J 2
(-2000 1725);
DISPLAY 0.617021 (-2000 1725);
PAINT SKYBLUE (-2000 1725);
FORCEPROP 2 LAST SEC 1
J 0
(-2000 2100);
DISPLAY 0.680851 (-2000 2100);
PAINT MONO (-2000 2100);
DISPLAY INVISIBLE (-2000 2100);
FORCEPROP 2 LAST SEC_TYPE 0402
J 0
(-2000 2075);
DISPLAY 1.021277 (-2000 2075);
PAINT ORANGE (-2000 2075);
DISPLAY INVISIBLE (-2000 2075);
FORCEPROP 2 LAST CDS_LIB mstr_discrete
J 0
(-1950 1875);
PAINT MONO (-1950 1875);
DISPLAY INVISIBLE (-1950 1875);
FORCEPROP 2 LAST CDS_LOCATION C2U4
J 0
(-2000 2025);
DISPLAY 0.617021 (-2000 2025);
PAINT AQUA (-2000 2025);
DISPLAY INVISIBLE (-2000 2025);
FORCEPROP 1 LAST PATH I257
J 2
(-2000 2025);
DISPLAY 0.978723 (-2000 2025);
PAINT WHITE (-2000 2025);
DISPLAY INVISIBLE (-2000 2025);
FORCEADD TAP..3
(-1900 1075);
FORCEPROP 3 LASTPIN (-1900 1025) SIG_NAME P3E_CPU0_PE1_PCH_RXP<0>
J 0
(-1890 1035);
DISPLAY 0.659574 (-1890 1035);
PAINT MONO (-1890 1035);
DISPLAY INVISIBLE (-1890 1035);
FORCEPROP 1 LASTPIN (-1900 1025) BN 0
R 1
J 0
(-1907 1013);
DISPLAY 0.617021 (-1907 1013);
PAINT GREEN (-1907 1013);
FORCEPROP 1 LAST PATH I258
J 0
(-1902 1075);
DISPLAY 0.872340 (-1902 1075);
PAINT GREEN (-1902 1075);
DISPLAY INVISIBLE (-1902 1075);
FORCEPROP 2 LAST CDS_LIB mstr_standard
J 0
(-1900 1075);
PAINT ORANGE (-1900 1075);
DISPLAY INVISIBLE (-1900 1075);
FORCEPROP 1 LAST BODY_TYPE PLUMBING
J 0
(-1850 1025);
DISPLAY 2.276596 (-1850 1025);
PAINT GREEN (-1850 1025);
DISPLAY INVISIBLE (-1850 1025);
FORCEPROP 1 LAST HDL_TAP TRUE
J 0
(-1580 945);
DISPLAY 2.276596 (-1580 945);
PAINT GREEN (-1580 945);
DISPLAY INVISIBLE (-1580 945);
FORCEADD TAP..7
(-1950 1275);
FORCEPROP 3 LASTPIN (-1950 1325) SIG_NAME P3E_CPU0_PE1_SS_RXN<0>
J 0
(-1940 1335);
DISPLAY 0.659574 (-1940 1335);
PAINT MONO (-1940 1335);
DISPLAY INVISIBLE (-1940 1335);
FORCEPROP 1 LASTPIN (-1950 1325) BN 0
R 1
J 0
(-1957 1273);
DISPLAY 0.617021 (-1957 1273);
PAINT GREEN (-1957 1273);
FORCEPROP 2 LAST CDS_LIB mstr_standard
J 0
(-1950 1275);
PAINT ORANGE (-1950 1275);
DISPLAY INVISIBLE (-1950 1275);
FORCEPROP 1 LAST PATH I259
J 0
(-1952 1275);
DISPLAY 0.872340 (-1952 1275);
PAINT GREEN (-1952 1275);
DISPLAY INVISIBLE (-1952 1275);
FORCEPROP 1 LAST BODY_TYPE PLUMBING
J 0
(-1900 1275);
DISPLAY 2.276596 (-1900 1275);
PAINT GREEN (-1900 1275);
DISPLAY INVISIBLE (-1900 1275);
FORCEPROP 1 LAST HDL_TAP TRUE
J 0
(-1630 1145);
DISPLAY 2.276596 (-1630 1145);
PAINT GREEN (-1630 1145);
DISPLAY INVISIBLE (-1630 1145);
FORCEADD CAP..1
R 2
(-2150 1525);
FORCEPROP 1 LAST PART_NUMBER A36096-155
R 1
J 2
(-2075 1650);
DISPLAY 0.617021 (-2075 1650);
PAINT BLUE (-2075 1650);
FORCEPROP 1 LAST VOLTAGE 16V
J 2
(-2200 1525);
DISPLAY 0.617021 (-2200 1525);
PAINT SKYBLUE (-2200 1525);
FORCEPROP 1 LAST VALUE 0.22UF
J 2
(-2200 1575);
DISPLAY 0.617021 (-2200 1575);
PAINT SKYBLUE (-2200 1575);
FORCEPROP 1 LASTPIN (-2150 1625) $PN 1
J 2
(-2155 1587);
DISPLAY 0.617021 (-2155 1587);
PAINT ORANGE (-2155 1587);
FORCEPROP 1 LAST PACK_TYPE 0402
J 2
(-2200 1375);
DISPLAY 0.617021 (-2200 1375);
PAINT SKYBLUE (-2200 1375);
FORCEPROP 1 LASTPIN (-2150 1425) $PN 2
J 2
(-2155 1435);
DISPLAY 0.617021 (-2155 1435);
PAINT ORANGE (-2155 1435);
FORCEPROP 1 LAST MATERIAL X7R
J 2
(-2200 1425);
DISPLAY 0.617021 (-2200 1425);
PAINT SKYBLUE (-2200 1425);
FORCEPROP 1 LAST TOLERANCE 10%
J 2
(-2200 1475);
DISPLAY 0.617021 (-2200 1475);
PAINT SKYBLUE (-2200 1475);
FORCEPROP 1 LAST LOCATION C2U6
J 2
(-2200 1625);
DISPLAY 0.617021 (-2200 1625);
PAINT AQUA (-2200 1625);
FORCEPROP 0 LAST GROUP PCIE_UPLINK
J 0
(-2307 1245);
DISPLAY 0.638298 (-2307 1245);
PAINT BROWN (-2307 1245);
DISPLAY BOTH (-2307 1245);
FORCEPROP 2 LAST CDS_LIB mstr_discrete
J 0
(-2150 1525);
PAINT MONO (-2150 1525);
DISPLAY INVISIBLE (-2150 1525);
FORCEPROP 2 LAST SEC_TYPE 0402
J 0
(-2200 1725);
DISPLAY 1.021277 (-2200 1725);
PAINT ORANGE (-2200 1725);
DISPLAY INVISIBLE (-2200 1725);
FORCEPROP 2 LAST SEC 1
J 0
(-2200 1750);
DISPLAY 0.680851 (-2200 1750);
PAINT MONO (-2200 1750);
DISPLAY INVISIBLE (-2200 1750);
FORCEPROP 2 LAST CDS_LOCATION C2U6
J 0
(-2200 1675);
DISPLAY 0.617021 (-2200 1675);
PAINT AQUA (-2200 1675);
DISPLAY INVISIBLE (-2200 1675);
FORCEPROP 1 LAST PATH I260
J 2
(-2200 1675);
DISPLAY 0.978723 (-2200 1675);
PAINT WHITE (-2200 1675);
DISPLAY INVISIBLE (-2200 1675);
FORCEADD TAP..3
(-2100 1075);
FORCEPROP 3 LASTPIN (-2100 1025) SIG_NAME P3E_CPU0_PE1_PCH_RXP<1>
J 0
(-2090 1035);
DISPLAY 0.659574 (-2090 1035);
PAINT MONO (-2090 1035);
DISPLAY INVISIBLE (-2090 1035);
FORCEPROP 1 LASTPIN (-2100 1025) BN 1
R 1
J 0
(-2107 1013);
DISPLAY 0.617021 (-2107 1013);
PAINT GREEN (-2107 1013);
FORCEPROP 1 LAST PATH I261
J 0
(-2102 1075);
DISPLAY 0.872340 (-2102 1075);
PAINT GREEN (-2102 1075);
DISPLAY INVISIBLE (-2102 1075);
FORCEPROP 2 LAST CDS_LIB mstr_standard
J 0
(-2100 1075);
PAINT ORANGE (-2100 1075);
DISPLAY INVISIBLE (-2100 1075);
FORCEPROP 1 LAST BODY_TYPE PLUMBING
J 0
(-2050 1025);
DISPLAY 2.276596 (-2050 1025);
PAINT GREEN (-2050 1025);
DISPLAY INVISIBLE (-2050 1025);
FORCEPROP 1 LAST HDL_TAP TRUE
J 0
(-1780 945);
DISPLAY 2.276596 (-1780 945);
PAINT GREEN (-1780 945);
DISPLAY INVISIBLE (-1780 945);
FORCEADD TAP..7
(-2150 1275);
FORCEPROP 3 LASTPIN (-2150 1325) SIG_NAME P3E_CPU0_PE1_SS_RXN<1>
J 0
(-2140 1335);
DISPLAY 0.659574 (-2140 1335);
PAINT MONO (-2140 1335);
DISPLAY INVISIBLE (-2140 1335);
FORCEPROP 1 LASTPIN (-2150 1325) BN 1
R 1
J 0
(-2157 1273);
DISPLAY 0.617021 (-2157 1273);
PAINT GREEN (-2157 1273);
FORCEPROP 2 LAST CDS_LIB mstr_standard
J 0
(-2150 1275);
PAINT ORANGE (-2150 1275);
DISPLAY INVISIBLE (-2150 1275);
FORCEPROP 1 LAST PATH I262
J 0
(-2152 1275);
DISPLAY 0.872340 (-2152 1275);
PAINT GREEN (-2152 1275);
DISPLAY INVISIBLE (-2152 1275);
FORCEPROP 1 LAST BODY_TYPE PLUMBING
J 0
(-2100 1275);
DISPLAY 2.276596 (-2100 1275);
PAINT GREEN (-2100 1275);
DISPLAY INVISIBLE (-2100 1275);
FORCEPROP 1 LAST HDL_TAP TRUE
J 0
(-1830 1145);
DISPLAY 2.276596 (-1830 1145);
PAINT GREEN (-1830 1145);
DISPLAY INVISIBLE (-1830 1145);
FORCEADD TAP..3
(-2300 1075);
FORCEPROP 3 LASTPIN (-2300 1025) SIG_NAME P3E_CPU0_PE1_PCH_RXP<2>
J 0
(-2290 1035);
DISPLAY 0.659574 (-2290 1035);
PAINT MONO (-2290 1035);
DISPLAY INVISIBLE (-2290 1035);
FORCEPROP 1 LASTPIN (-2300 1025) BN 2
R 1
J 0
(-2307 1013);
DISPLAY 0.617021 (-2307 1013);
PAINT GREEN (-2307 1013);
FORCEPROP 1 LAST PATH I263
J 0
(-2302 1075);
DISPLAY 0.872340 (-2302 1075);
PAINT GREEN (-2302 1075);
DISPLAY INVISIBLE (-2302 1075);
FORCEPROP 2 LAST CDS_LIB mstr_standard
J 0
(-2300 1075);
PAINT ORANGE (-2300 1075);
DISPLAY INVISIBLE (-2300 1075);
FORCEPROP 1 LAST BODY_TYPE PLUMBING
J 0
(-2250 1025);
DISPLAY 2.276596 (-2250 1025);
PAINT GREEN (-2250 1025);
DISPLAY INVISIBLE (-2250 1025);
FORCEPROP 1 LAST HDL_TAP TRUE
J 0
(-1980 945);
DISPLAY 2.276596 (-1980 945);
PAINT GREEN (-1980 945);
DISPLAY INVISIBLE (-1980 945);
FORCEADD CAP..1
R 2
(-2350 1875);
FORCEPROP 0 LAST GROUP PCIE_UPLINK
J 0
(-2507 2070);
DISPLAY 0.638298 (-2507 2070);
PAINT BROWN (-2507 2070);
DISPLAY BOTH (-2507 2070);
FORCEPROP 1 LAST PART_NUMBER A36096-155
R 1
J 2
(-2275 2025);
DISPLAY 0.617021 (-2275 2025);
PAINT BLUE (-2275 2025);
FORCEPROP 1 LASTPIN (-2350 1975) $PN 1
J 2
(-2355 1937);
DISPLAY 0.617021 (-2355 1937);
PAINT ORANGE (-2355 1937);
FORCEPROP 1 LAST LOCATION C2U8
J 2
(-2400 1975);
DISPLAY 0.617021 (-2400 1975);
PAINT AQUA (-2400 1975);
FORCEPROP 1 LAST PACK_TYPE 0402
J 2
(-2400 1725);
DISPLAY 0.617021 (-2400 1725);
PAINT SKYBLUE (-2400 1725);
FORCEPROP 1 LASTPIN (-2350 1775) $PN 2
J 2
(-2355 1785);
DISPLAY 0.617021 (-2355 1785);
PAINT ORANGE (-2355 1785);
FORCEPROP 1 LAST MATERIAL X7R
J 2
(-2400 1775);
DISPLAY 0.617021 (-2400 1775);
PAINT SKYBLUE (-2400 1775);
FORCEPROP 1 LAST VALUE 0.22UF
J 2
(-2400 1925);
DISPLAY 0.617021 (-2400 1925);
PAINT SKYBLUE (-2400 1925);
FORCEPROP 1 LAST VOLTAGE 16V
J 2
(-2400 1875);
DISPLAY 0.617021 (-2400 1875);
PAINT SKYBLUE (-2400 1875);
FORCEPROP 1 LAST TOLERANCE 10%
J 2
(-2400 1825);
DISPLAY 0.617021 (-2400 1825);
PAINT SKYBLUE (-2400 1825);
FORCEPROP 2 LAST SEC 1
J 0
(-2400 2100);
DISPLAY 0.680851 (-2400 2100);
PAINT MONO (-2400 2100);
DISPLAY INVISIBLE (-2400 2100);
FORCEPROP 2 LAST SEC_TYPE 0402
J 0
(-2400 2075);
DISPLAY 1.021277 (-2400 2075);
PAINT ORANGE (-2400 2075);
DISPLAY INVISIBLE (-2400 2075);
FORCEPROP 1 LAST PATH I264
J 2
(-2400 2025);
DISPLAY 0.978723 (-2400 2025);
PAINT WHITE (-2400 2025);
DISPLAY INVISIBLE (-2400 2025);
FORCEPROP 2 LAST CDS_LOCATION C2U8
J 0
(-2400 2025);
DISPLAY 0.617021 (-2400 2025);
PAINT AQUA (-2400 2025);
DISPLAY INVISIBLE (-2400 2025);
FORCEPROP 2 LAST CDS_LIB mstr_discrete
J 0
(-2350 1875);
PAINT MONO (-2350 1875);
DISPLAY INVISIBLE (-2350 1875);
FORCEADD CAP..1
R 2
(-2750 1875);
FORCEPROP 0 LAST GROUP PCIE_UPLINK
J 0
(-2907 2070);
DISPLAY 0.638298 (-2907 2070);
PAINT BROWN (-2907 2070);
DISPLAY BOTH (-2907 2070);
FORCEPROP 1 LASTPIN (-2750 1975) $PN 1
J 2
(-2755 1937);
DISPLAY 0.617021 (-2755 1937);
PAINT ORANGE (-2755 1937);
FORCEPROP 1 LASTPIN (-2750 1775) $PN 2
J 2
(-2755 1785);
DISPLAY 0.617021 (-2755 1785);
PAINT ORANGE (-2755 1785);
FORCEPROP 1 LAST VALUE 0.22UF
J 2
(-2800 1925);
DISPLAY 0.617021 (-2800 1925);
PAINT SKYBLUE (-2800 1925);
FORCEPROP 1 LAST MATERIAL X7R
J 2
(-2800 1775);
DISPLAY 0.617021 (-2800 1775);
PAINT SKYBLUE (-2800 1775);
FORCEPROP 1 LAST PACK_TYPE 0402
J 2
(-2800 1725);
DISPLAY 0.617021 (-2800 1725);
PAINT SKYBLUE (-2800 1725);
FORCEPROP 1 LAST VOLTAGE 16V
J 2
(-2800 1875);
DISPLAY 0.617021 (-2800 1875);
PAINT SKYBLUE (-2800 1875);
FORCEPROP 1 LAST PART_NUMBER A36096-155
R 1
J 2
(-2675 2025);
DISPLAY 0.617021 (-2675 2025);
PAINT BLUE (-2675 2025);
FORCEPROP 1 LAST TOLERANCE 10%
J 2
(-2800 1825);
DISPLAY 0.617021 (-2800 1825);
PAINT SKYBLUE (-2800 1825);
FORCEPROP 1 LAST LOCATION C2U12
J 2
(-2800 1975);
DISPLAY 0.617021 (-2800 1975);
PAINT AQUA (-2800 1975);
FORCEPROP 2 LAST SEC 1
J 0
(-2800 2100);
DISPLAY 0.680851 (-2800 2100);
PAINT MONO (-2800 2100);
DISPLAY INVISIBLE (-2800 2100);
FORCEPROP 2 LAST SEC_TYPE 0402
J 0
(-2800 2075);
DISPLAY 1.021277 (-2800 2075);
PAINT ORANGE (-2800 2075);
DISPLAY INVISIBLE (-2800 2075);
FORCEPROP 2 LAST CDS_LIB mstr_discrete
J 0
(-2750 1875);
PAINT MONO (-2750 1875);
DISPLAY INVISIBLE (-2750 1875);
FORCEPROP 1 LAST PATH I265
J 2
(-2800 2025);
DISPLAY 0.978723 (-2800 2025);
PAINT WHITE (-2800 2025);
DISPLAY INVISIBLE (-2800 2025);
FORCEPROP 2 LAST CDS_LOCATION C2U12
J 0
(-2800 2025);
DISPLAY 0.617021 (-2800 2025);
PAINT AQUA (-2800 2025);
DISPLAY INVISIBLE (-2800 2025);
FORCEADD TAP..7
(-2350 1275);
FORCEPROP 3 LASTPIN (-2350 1325) SIG_NAME P3E_CPU0_PE1_SS_RXN<2>
J 0
(-2340 1335);
DISPLAY 0.659574 (-2340 1335);
PAINT MONO (-2340 1335);
DISPLAY INVISIBLE (-2340 1335);
FORCEPROP 1 LASTPIN (-2350 1325) BN 2
R 1
J 0
(-2357 1273);
DISPLAY 0.617021 (-2357 1273);
PAINT GREEN (-2357 1273);
FORCEPROP 2 LAST CDS_LIB mstr_standard
J 0
(-2350 1275);
PAINT ORANGE (-2350 1275);
DISPLAY INVISIBLE (-2350 1275);
FORCEPROP 1 LAST PATH I266
J 0
(-2352 1275);
DISPLAY 0.872340 (-2352 1275);
PAINT GREEN (-2352 1275);
DISPLAY INVISIBLE (-2352 1275);
FORCEPROP 1 LAST BODY_TYPE PLUMBING
J 0
(-2300 1275);
DISPLAY 2.276596 (-2300 1275);
PAINT GREEN (-2300 1275);
DISPLAY INVISIBLE (-2300 1275);
FORCEPROP 1 LAST HDL_TAP TRUE
J 0
(-2030 1145);
DISPLAY 2.276596 (-2030 1145);
PAINT GREEN (-2030 1145);
DISPLAY INVISIBLE (-2030 1145);
FORCEADD CAP..1
R 2
(-2550 1525);
FORCEPROP 1 LAST PACK_TYPE 0402
J 2
(-2600 1375);
DISPLAY 0.617021 (-2600 1375);
PAINT SKYBLUE (-2600 1375);
FORCEPROP 1 LAST VALUE 0.22UF
J 2
(-2600 1575);
DISPLAY 0.617021 (-2600 1575);
PAINT SKYBLUE (-2600 1575);
FORCEPROP 1 LAST MATERIAL X7R
J 2
(-2600 1425);
DISPLAY 0.617021 (-2600 1425);
PAINT SKYBLUE (-2600 1425);
FORCEPROP 1 LAST TOLERANCE 10%
J 2
(-2600 1475);
DISPLAY 0.617021 (-2600 1475);
PAINT SKYBLUE (-2600 1475);
FORCEPROP 1 LASTPIN (-2550 1425) $PN 2
J 2
(-2555 1435);
DISPLAY 0.617021 (-2555 1435);
PAINT ORANGE (-2555 1435);
FORCEPROP 1 LASTPIN (-2550 1625) $PN 1
J 2
(-2555 1587);
DISPLAY 0.617021 (-2555 1587);
PAINT ORANGE (-2555 1587);
FORCEPROP 1 LAST VOLTAGE 16V
J 2
(-2600 1525);
DISPLAY 0.617021 (-2600 1525);
PAINT SKYBLUE (-2600 1525);
FORCEPROP 1 LAST LOCATION C2U10
J 2
(-2600 1625);
DISPLAY 0.617021 (-2600 1625);
PAINT AQUA (-2600 1625);
FORCEPROP 1 LAST PART_NUMBER A36096-155
R 1
J 2
(-2475 1650);
DISPLAY 0.617021 (-2475 1650);
PAINT BLUE (-2475 1650);
FORCEPROP 0 LAST GROUP PCIE_UPLINK
J 0
(-2707 1245);
DISPLAY 0.638298 (-2707 1245);
PAINT BROWN (-2707 1245);
DISPLAY BOTH (-2707 1245);
FORCEPROP 1 LAST PATH I267
J 2
(-2600 1675);
DISPLAY 0.978723 (-2600 1675);
PAINT WHITE (-2600 1675);
DISPLAY INVISIBLE (-2600 1675);
FORCEPROP 2 LAST CDS_LOCATION C2U10
J 0
(-2600 1675);
DISPLAY 0.617021 (-2600 1675);
PAINT AQUA (-2600 1675);
DISPLAY INVISIBLE (-2600 1675);
FORCEPROP 2 LAST SEC 1
J 0
(-2600 1750);
DISPLAY 0.680851 (-2600 1750);
PAINT MONO (-2600 1750);
DISPLAY INVISIBLE (-2600 1750);
FORCEPROP 2 LAST SEC_TYPE 0402
J 0
(-2600 1725);
DISPLAY 1.021277 (-2600 1725);
PAINT ORANGE (-2600 1725);
DISPLAY INVISIBLE (-2600 1725);
FORCEPROP 2 LAST CDS_LIB mstr_discrete
J 0
(-2550 1525);
PAINT MONO (-2550 1525);
DISPLAY INVISIBLE (-2550 1525);
FORCEADD TAP..7
(-2550 1275);
FORCEPROP 3 LASTPIN (-2550 1325) SIG_NAME P3E_CPU0_PE1_SS_RXN<3>
J 0
(-2540 1335);
DISPLAY 0.659574 (-2540 1335);
PAINT MONO (-2540 1335);
DISPLAY INVISIBLE (-2540 1335);
FORCEPROP 1 LASTPIN (-2550 1325) BN 3
R 1
J 0
(-2557 1273);
DISPLAY 0.617021 (-2557 1273);
PAINT GREEN (-2557 1273);
FORCEPROP 2 LAST CDS_LIB mstr_standard
J 0
(-2550 1275);
PAINT ORANGE (-2550 1275);
DISPLAY INVISIBLE (-2550 1275);
FORCEPROP 1 LAST PATH I268
J 0
(-2552 1275);
DISPLAY 0.872340 (-2552 1275);
PAINT GREEN (-2552 1275);
DISPLAY INVISIBLE (-2552 1275);
FORCEPROP 1 LAST BODY_TYPE PLUMBING
J 0
(-2500 1275);
DISPLAY 2.276596 (-2500 1275);
PAINT GREEN (-2500 1275);
DISPLAY INVISIBLE (-2500 1275);
FORCEPROP 1 LAST HDL_TAP TRUE
J 0
(-2230 1145);
DISPLAY 2.276596 (-2230 1145);
PAINT GREEN (-2230 1145);
DISPLAY INVISIBLE (-2230 1145);
FORCEADD TAP..3
(-2500 1075);
FORCEPROP 3 LASTPIN (-2500 1025) SIG_NAME P3E_CPU0_PE1_PCH_RXP<3>
J 0
(-2490 1035);
DISPLAY 0.659574 (-2490 1035);
PAINT MONO (-2490 1035);
DISPLAY INVISIBLE (-2490 1035);
FORCEPROP 1 LASTPIN (-2500 1025) BN 3
R 1
J 0
(-2507 1013);
DISPLAY 0.617021 (-2507 1013);
PAINT GREEN (-2507 1013);
FORCEPROP 1 LAST PATH I269
J 0
(-2502 1075);
DISPLAY 0.872340 (-2502 1075);
PAINT GREEN (-2502 1075);
DISPLAY INVISIBLE (-2502 1075);
FORCEPROP 2 LAST CDS_LIB mstr_standard
J 0
(-2500 1075);
PAINT ORANGE (-2500 1075);
DISPLAY INVISIBLE (-2500 1075);
FORCEPROP 1 LAST BODY_TYPE PLUMBING
J 0
(-2450 1025);
DISPLAY 2.276596 (-2450 1025);
PAINT GREEN (-2450 1025);
DISPLAY INVISIBLE (-2450 1025);
FORCEPROP 1 LAST HDL_TAP TRUE
J 0
(-2180 945);
DISPLAY 2.276596 (-2180 945);
PAINT GREEN (-2180 945);
DISPLAY INVISIBLE (-2180 945);
FORCEADD TAP..3
(-2700 1075);
FORCEPROP 3 LASTPIN (-2700 1025) SIG_NAME P3E_CPU0_PE1_PCH_RXP<4>
J 0
(-2690 1035);
DISPLAY 0.659574 (-2690 1035);
PAINT MONO (-2690 1035);
DISPLAY INVISIBLE (-2690 1035);
FORCEPROP 1 LASTPIN (-2700 1025) BN 4
R 1
J 0
(-2707 1013);
DISPLAY 0.617021 (-2707 1013);
PAINT GREEN (-2707 1013);
FORCEPROP 2 LAST CDS_LIB mstr_standard
J 0
(-2700 1075);
PAINT ORANGE (-2700 1075);
DISPLAY INVISIBLE (-2700 1075);
FORCEPROP 1 LAST PATH I270
J 0
(-2702 1075);
DISPLAY 0.872340 (-2702 1075);
PAINT GREEN (-2702 1075);
DISPLAY INVISIBLE (-2702 1075);
FORCEPROP 1 LAST BODY_TYPE PLUMBING
J 0
(-2650 1025);
DISPLAY 2.276596 (-2650 1025);
PAINT GREEN (-2650 1025);
DISPLAY INVISIBLE (-2650 1025);
FORCEPROP 1 LAST HDL_TAP TRUE
J 0
(-2380 945);
DISPLAY 2.276596 (-2380 945);
PAINT GREEN (-2380 945);
DISPLAY INVISIBLE (-2380 945);
FORCEADD TAP..7
(-2750 1275);
FORCEPROP 3 LASTPIN (-2750 1325) SIG_NAME P3E_CPU0_PE1_SS_RXN<4>
J 0
(-2740 1335);
DISPLAY 0.659574 (-2740 1335);
PAINT MONO (-2740 1335);
DISPLAY INVISIBLE (-2740 1335);
FORCEPROP 1 LASTPIN (-2750 1325) BN 4
R 1
J 0
(-2757 1273);
DISPLAY 0.617021 (-2757 1273);
PAINT GREEN (-2757 1273);
FORCEPROP 2 LAST CDS_LIB mstr_standard
J 0
(-2750 1275);
PAINT ORANGE (-2750 1275);
DISPLAY INVISIBLE (-2750 1275);
FORCEPROP 1 LAST PATH I271
J 0
(-2752 1275);
DISPLAY 0.872340 (-2752 1275);
PAINT GREEN (-2752 1275);
DISPLAY INVISIBLE (-2752 1275);
FORCEPROP 1 LAST BODY_TYPE PLUMBING
J 0
(-2700 1275);
DISPLAY 2.276596 (-2700 1275);
PAINT GREEN (-2700 1275);
DISPLAY INVISIBLE (-2700 1275);
FORCEPROP 1 LAST HDL_TAP TRUE
J 0
(-2430 1145);
DISPLAY 2.276596 (-2430 1145);
PAINT GREEN (-2430 1145);
DISPLAY INVISIBLE (-2430 1145);
FORCEADD CAP..1
R 2
(-1900 875);
FORCEPROP 1 LAST PACK_TYPE 0402
J 2
(-1950 725);
DISPLAY 0.617021 (-1950 725);
PAINT SKYBLUE (-1950 725);
FORCEPROP 1 LAST LOCATION C2U3
J 2
(-1950 975);
DISPLAY 0.617021 (-1950 975);
PAINT AQUA (-1950 975);
FORCEPROP 1 LAST TOLERANCE 10%
J 2
(-1950 825);
DISPLAY 0.617021 (-1950 825);
PAINT SKYBLUE (-1950 825);
FORCEPROP 1 LAST VALUE 0.22UF
J 2
(-1950 925);
DISPLAY 0.617021 (-1950 925);
PAINT SKYBLUE (-1950 925);
FORCEPROP 1 LASTPIN (-1900 975) $PN 1
J 2
(-1905 937);
DISPLAY 0.617021 (-1905 937);
PAINT ORANGE (-1905 937);
FORCEPROP 1 LASTPIN (-1900 775) $PN 2
J 2
(-1905 785);
DISPLAY 0.617021 (-1905 785);
PAINT ORANGE (-1905 785);
FORCEPROP 1 LAST MATERIAL X7R
J 2
(-1950 775);
DISPLAY 0.617021 (-1950 775);
PAINT SKYBLUE (-1950 775);
FORCEPROP 1 LAST VOLTAGE 16V
J 2
(-1950 875);
DISPLAY 0.617021 (-1950 875);
PAINT SKYBLUE (-1950 875);
FORCEPROP 1 LAST PART_NUMBER A36096-155
R 1
J 2
(-1825 1000);
DISPLAY 0.617021 (-1825 1000);
PAINT BLUE (-1825 1000);
FORCEPROP 0 LAST GROUP PCIE_UPLINK
J 0
(-2057 1070);
DISPLAY 0.638298 (-2057 1070);
PAINT BROWN (-2057 1070);
DISPLAY BOTH (-2057 1070);
FORCEPROP 2 LAST SEC 1
J 0
(-1950 1100);
DISPLAY 0.680851 (-1950 1100);
PAINT MONO (-1950 1100);
DISPLAY INVISIBLE (-1950 1100);
FORCEPROP 2 LAST SEC_TYPE 0402
J 0
(-1950 1075);
DISPLAY 1.021277 (-1950 1075);
PAINT ORANGE (-1950 1075);
DISPLAY INVISIBLE (-1950 1075);
FORCEPROP 1 LAST PATH I272
J 2
(-1950 1025);
DISPLAY 0.978723 (-1950 1025);
PAINT WHITE (-1950 1025);
DISPLAY INVISIBLE (-1950 1025);
FORCEPROP 2 LAST CDS_LOCATION C2U3
J 0
(-1950 1025);
DISPLAY 0.617021 (-1950 1025);
PAINT AQUA (-1950 1025);
DISPLAY INVISIBLE (-1950 1025);
FORCEPROP 2 LAST CDS_LIB mstr_discrete
J 0
(-1900 875);
PAINT MONO (-1900 875);
DISPLAY INVISIBLE (-1900 875);
FORCEADD TAP..7
(-1900 275);
FORCEPROP 3 LASTPIN (-1900 325) SIG_NAME P3E_CPU0_PE1_SS_RXP<0>
J 0
(-1890 335);
DISPLAY 0.659574 (-1890 335);
PAINT MONO (-1890 335);
DISPLAY INVISIBLE (-1890 335);
FORCEPROP 1 LASTPIN (-1900 325) BN 0
R 1
J 0
(-1907 273);
DISPLAY 0.617021 (-1907 273);
PAINT GREEN (-1907 273);
FORCEPROP 2 LAST CDS_LIB mstr_standard
J 0
(-1900 275);
PAINT ORANGE (-1900 275);
DISPLAY INVISIBLE (-1900 275);
FORCEPROP 1 LAST PATH I273
J 0
(-1902 275);
DISPLAY 0.872340 (-1902 275);
PAINT GREEN (-1902 275);
DISPLAY INVISIBLE (-1902 275);
FORCEPROP 1 LAST BODY_TYPE PLUMBING
J 0
(-1850 275);
DISPLAY 2.276596 (-1850 275);
PAINT GREEN (-1850 275);
DISPLAY INVISIBLE (-1850 275);
FORCEPROP 1 LAST HDL_TAP TRUE
J 0
(-1580 145);
DISPLAY 2.276596 (-1580 145);
PAINT GREEN (-1580 145);
DISPLAY INVISIBLE (-1580 145);
FORCEADD CAP..1
R 2
(-2100 525);
FORCEPROP 1 LAST MATERIAL X7R
J 2
(-2150 425);
DISPLAY 0.617021 (-2150 425);
PAINT SKYBLUE (-2150 425);
FORCEPROP 1 LAST PACK_TYPE 0402
J 2
(-2150 375);
DISPLAY 0.617021 (-2150 375);
PAINT SKYBLUE (-2150 375);
FORCEPROP 1 LAST TOLERANCE 10%
J 2
(-2150 475);
DISPLAY 0.617021 (-2150 475);
PAINT SKYBLUE (-2150 475);
FORCEPROP 1 LASTPIN (-2100 425) $PN 2
J 2
(-2105 435);
DISPLAY 0.617021 (-2105 435);
PAINT ORANGE (-2105 435);
FORCEPROP 1 LASTPIN (-2100 625) $PN 1
J 2
(-2105 587);
DISPLAY 0.617021 (-2105 587);
PAINT ORANGE (-2105 587);
FORCEPROP 1 LAST PART_NUMBER A36096-155
R 1
J 2
(-2025 625);
DISPLAY 0.617021 (-2025 625);
PAINT BLUE (-2025 625);
FORCEPROP 1 LAST VOLTAGE 16V
J 2
(-2150 525);
DISPLAY 0.617021 (-2150 525);
PAINT SKYBLUE (-2150 525);
FORCEPROP 1 LAST LOCATION C2U5
J 2
(-2150 625);
DISPLAY 0.617021 (-2150 625);
PAINT AQUA (-2150 625);
FORCEPROP 1 LAST VALUE 0.22UF
J 2
(-2150 575);
DISPLAY 0.617021 (-2150 575);
PAINT SKYBLUE (-2150 575);
FORCEPROP 0 LAST GROUP PCIE_UPLINK
J 0
(-2257 320);
DISPLAY 0.638298 (-2257 320);
PAINT BROWN (-2257 320);
DISPLAY BOTH (-2257 320);
FORCEPROP 2 LAST CDS_LIB mstr_discrete
J 0
(-2100 525);
PAINT MONO (-2100 525);
DISPLAY INVISIBLE (-2100 525);
FORCEPROP 2 LAST SEC_TYPE 0402
J 0
(-2150 725);
DISPLAY 1.021277 (-2150 725);
PAINT ORANGE (-2150 725);
DISPLAY INVISIBLE (-2150 725);
FORCEPROP 2 LAST CDS_LOCATION C2U5
J 0
(-2150 675);
DISPLAY 0.617021 (-2150 675);
PAINT AQUA (-2150 675);
DISPLAY INVISIBLE (-2150 675);
FORCEPROP 1 LAST PATH I274
J 2
(-2150 675);
DISPLAY 0.978723 (-2150 675);
PAINT WHITE (-2150 675);
DISPLAY INVISIBLE (-2150 675);
FORCEPROP 2 LAST SEC 1
J 0
(-2150 750);
DISPLAY 0.680851 (-2150 750);
PAINT MONO (-2150 750);
DISPLAY INVISIBLE (-2150 750);
FORCEADD TAP..7
(-2100 275);
FORCEPROP 3 LASTPIN (-2100 325) SIG_NAME P3E_CPU0_PE1_SS_RXP<1>
J 0
(-2090 335);
DISPLAY 0.659574 (-2090 335);
PAINT MONO (-2090 335);
DISPLAY INVISIBLE (-2090 335);
FORCEPROP 1 LASTPIN (-2100 325) BN 1
R 1
J 0
(-2107 273);
DISPLAY 0.617021 (-2107 273);
PAINT GREEN (-2107 273);
FORCEPROP 2 LAST CDS_LIB mstr_standard
J 0
(-2100 275);
PAINT ORANGE (-2100 275);
DISPLAY INVISIBLE (-2100 275);
FORCEPROP 1 LAST PATH I275
J 0
(-2102 275);
DISPLAY 0.872340 (-2102 275);
PAINT GREEN (-2102 275);
DISPLAY INVISIBLE (-2102 275);
FORCEPROP 1 LAST BODY_TYPE PLUMBING
J 0
(-2050 275);
DISPLAY 2.276596 (-2050 275);
PAINT GREEN (-2050 275);
DISPLAY INVISIBLE (-2050 275);
FORCEPROP 1 LAST HDL_TAP TRUE
J 0
(-1780 145);
DISPLAY 2.276596 (-1780 145);
PAINT GREEN (-1780 145);
DISPLAY INVISIBLE (-1780 145);
FORCEADD TAP..7
(-2300 275);
FORCEPROP 3 LASTPIN (-2300 325) SIG_NAME P3E_CPU0_PE1_SS_RXP<2>
J 0
(-2290 335);
DISPLAY 0.659574 (-2290 335);
PAINT MONO (-2290 335);
DISPLAY INVISIBLE (-2290 335);
FORCEPROP 1 LASTPIN (-2300 325) BN 2
R 1
J 0
(-2307 273);
DISPLAY 0.617021 (-2307 273);
PAINT GREEN (-2307 273);
FORCEPROP 1 LAST PATH I276
J 0
(-2302 275);
DISPLAY 0.872340 (-2302 275);
PAINT GREEN (-2302 275);
DISPLAY INVISIBLE (-2302 275);
FORCEPROP 2 LAST CDS_LIB mstr_standard
J 0
(-2300 275);
PAINT ORANGE (-2300 275);
DISPLAY INVISIBLE (-2300 275);
FORCEPROP 1 LAST BODY_TYPE PLUMBING
J 0
(-2250 275);
DISPLAY 2.276596 (-2250 275);
PAINT GREEN (-2250 275);
DISPLAY INVISIBLE (-2250 275);
FORCEPROP 1 LAST HDL_TAP TRUE
J 0
(-1980 145);
DISPLAY 2.276596 (-1980 145);
PAINT GREEN (-1980 145);
DISPLAY INVISIBLE (-1980 145);
FORCEADD CAP..1
R 2
(-2300 875);
FORCEPROP 1 LAST TOLERANCE 10%
J 2
(-2350 825);
DISPLAY 0.617021 (-2350 825);
PAINT SKYBLUE (-2350 825);
FORCEPROP 1 LAST PACK_TYPE 0402
J 2
(-2350 725);
DISPLAY 0.617021 (-2350 725);
PAINT SKYBLUE (-2350 725);
FORCEPROP 1 LAST MATERIAL X7R
J 2
(-2350 775);
DISPLAY 0.617021 (-2350 775);
PAINT SKYBLUE (-2350 775);
FORCEPROP 1 LASTPIN (-2300 975) $PN 1
J 2
(-2305 937);
DISPLAY 0.617021 (-2305 937);
PAINT ORANGE (-2305 937);
FORCEPROP 1 LASTPIN (-2300 775) $PN 2
J 2
(-2305 785);
DISPLAY 0.617021 (-2305 785);
PAINT ORANGE (-2305 785);
FORCEPROP 1 LAST LOCATION C2U7
J 2
(-2350 975);
DISPLAY 0.617021 (-2350 975);
PAINT AQUA (-2350 975);
FORCEPROP 1 LAST VALUE 0.22UF
J 2
(-2350 925);
DISPLAY 0.617021 (-2350 925);
PAINT SKYBLUE (-2350 925);
FORCEPROP 1 LAST VOLTAGE 16V
J 2
(-2350 875);
DISPLAY 0.617021 (-2350 875);
PAINT SKYBLUE (-2350 875);
FORCEPROP 0 LAST GROUP PCIE_UPLINK
J 0
(-2457 1070);
DISPLAY 0.638298 (-2457 1070);
PAINT BROWN (-2457 1070);
DISPLAY BOTH (-2457 1070);
FORCEPROP 1 LAST PART_NUMBER A36096-155
R 1
J 2
(-2225 1000);
DISPLAY 0.617021 (-2225 1000);
PAINT BLUE (-2225 1000);
FORCEPROP 2 LAST SEC_TYPE 0402
J 0
(-2350 1075);
DISPLAY 1.021277 (-2350 1075);
PAINT ORANGE (-2350 1075);
DISPLAY INVISIBLE (-2350 1075);
FORCEPROP 2 LAST SEC 1
J 0
(-2350 1100);
DISPLAY 0.680851 (-2350 1100);
PAINT MONO (-2350 1100);
DISPLAY INVISIBLE (-2350 1100);
FORCEPROP 2 LAST CDS_LIB mstr_discrete
J 0
(-2300 875);
PAINT MONO (-2300 875);
DISPLAY INVISIBLE (-2300 875);
FORCEPROP 2 LAST CDS_LOCATION C2U7
J 0
(-2350 1025);
DISPLAY 0.617021 (-2350 1025);
PAINT AQUA (-2350 1025);
DISPLAY INVISIBLE (-2350 1025);
FORCEPROP 1 LAST PATH I277
J 2
(-2350 1025);
DISPLAY 0.978723 (-2350 1025);
PAINT WHITE (-2350 1025);
DISPLAY INVISIBLE (-2350 1025);
FORCEADD CAP..1
R 2
(-2700 875);
FORCEPROP 1 LAST PACK_TYPE 0402
J 2
(-2750 725);
DISPLAY 0.617021 (-2750 725);
PAINT SKYBLUE (-2750 725);
FORCEPROP 1 LAST LOCATION C2U11
J 2
(-2750 975);
DISPLAY 0.617021 (-2750 975);
PAINT AQUA (-2750 975);
FORCEPROP 1 LASTPIN (-2700 975) $PN 1
J 2
(-2705 937);
DISPLAY 0.617021 (-2705 937);
PAINT ORANGE (-2705 937);
FORCEPROP 1 LASTPIN (-2700 775) $PN 2
J 2
(-2705 785);
DISPLAY 0.617021 (-2705 785);
PAINT ORANGE (-2705 785);
FORCEPROP 1 LAST TOLERANCE 10%
J 2
(-2750 825);
DISPLAY 0.617021 (-2750 825);
PAINT SKYBLUE (-2750 825);
FORCEPROP 1 LAST VOLTAGE 16V
J 2
(-2750 875);
DISPLAY 0.617021 (-2750 875);
PAINT SKYBLUE (-2750 875);
FORCEPROP 1 LAST MATERIAL X7R
J 2
(-2750 775);
DISPLAY 0.617021 (-2750 775);
PAINT SKYBLUE (-2750 775);
FORCEPROP 1 LAST VALUE 0.22UF
J 2
(-2750 925);
DISPLAY 0.617021 (-2750 925);
PAINT SKYBLUE (-2750 925);
FORCEPROP 1 LAST PART_NUMBER A36096-155
R 1
J 2
(-2625 1000);
DISPLAY 0.617021 (-2625 1000);
PAINT BLUE (-2625 1000);
FORCEPROP 0 LAST GROUP PCIE_UPLINK
J 0
(-2857 1070);
DISPLAY 0.638298 (-2857 1070);
PAINT BROWN (-2857 1070);
DISPLAY BOTH (-2857 1070);
FORCEPROP 2 LAST SEC 1
J 0
(-2750 1100);
DISPLAY 0.680851 (-2750 1100);
PAINT MONO (-2750 1100);
DISPLAY INVISIBLE (-2750 1100);
FORCEPROP 2 LAST SEC_TYPE 0402
J 0
(-2750 1075);
DISPLAY 1.021277 (-2750 1075);
PAINT ORANGE (-2750 1075);
DISPLAY INVISIBLE (-2750 1075);
FORCEPROP 2 LAST CDS_LIB mstr_discrete
J 0
(-2700 875);
PAINT MONO (-2700 875);
DISPLAY INVISIBLE (-2700 875);
FORCEPROP 2 LAST CDS_LOCATION C2U11
J 0
(-2750 1025);
DISPLAY 0.617021 (-2750 1025);
PAINT AQUA (-2750 1025);
DISPLAY INVISIBLE (-2750 1025);
FORCEPROP 1 LAST PATH I278
J 2
(-2750 1025);
DISPLAY 0.978723 (-2750 1025);
PAINT WHITE (-2750 1025);
DISPLAY INVISIBLE (-2750 1025);
FORCEADD CAP..1
R 2
(-2500 525);
FORCEPROP 1 LAST VALUE 0.22UF
J 2
(-2550 575);
DISPLAY 0.617021 (-2550 575);
PAINT SKYBLUE (-2550 575);
FORCEPROP 1 LASTPIN (-2500 625) $PN 1
J 2
(-2505 587);
DISPLAY 0.617021 (-2505 587);
PAINT ORANGE (-2505 587);
FORCEPROP 1 LAST LOCATION C2U9
J 2
(-2550 625);
DISPLAY 0.617021 (-2550 625);
PAINT AQUA (-2550 625);
FORCEPROP 1 LASTPIN (-2500 425) $PN 2
J 2
(-2505 435);
DISPLAY 0.617021 (-2505 435);
PAINT ORANGE (-2505 435);
FORCEPROP 1 LAST TOLERANCE 10%
J 2
(-2550 475);
DISPLAY 0.617021 (-2550 475);
PAINT SKYBLUE (-2550 475);
FORCEPROP 1 LAST PACK_TYPE 0402
J 2
(-2550 375);
DISPLAY 0.617021 (-2550 375);
PAINT SKYBLUE (-2550 375);
FORCEPROP 1 LAST MATERIAL X7R
J 2
(-2550 425);
DISPLAY 0.617021 (-2550 425);
PAINT SKYBLUE (-2550 425);
FORCEPROP 1 LAST VOLTAGE 16V
J 2
(-2550 525);
DISPLAY 0.617021 (-2550 525);
PAINT SKYBLUE (-2550 525);
FORCEPROP 1 LAST PART_NUMBER A36096-155
R 1
J 2
(-2425 625);
DISPLAY 0.617021 (-2425 625);
PAINT BLUE (-2425 625);
FORCEPROP 0 LAST GROUP PCIE_UPLINK
J 0
(-2657 320);
DISPLAY 0.638298 (-2657 320);
PAINT BROWN (-2657 320);
DISPLAY BOTH (-2657 320);
FORCEPROP 1 LAST PATH I279
J 2
(-2550 675);
DISPLAY 0.978723 (-2550 675);
PAINT WHITE (-2550 675);
DISPLAY INVISIBLE (-2550 675);
FORCEPROP 2 LAST CDS_LOCATION C2U9
J 0
(-2550 675);
DISPLAY 0.617021 (-2550 675);
PAINT AQUA (-2550 675);
DISPLAY INVISIBLE (-2550 675);
FORCEPROP 2 LAST CDS_LIB mstr_discrete
J 0
(-2500 525);
PAINT MONO (-2500 525);
DISPLAY INVISIBLE (-2500 525);
FORCEPROP 2 LAST SEC_TYPE 0402
J 0
(-2550 725);
DISPLAY 1.021277 (-2550 725);
PAINT ORANGE (-2550 725);
DISPLAY INVISIBLE (-2550 725);
FORCEPROP 2 LAST SEC 1
J 0
(-2550 750);
DISPLAY 0.680851 (-2550 750);
PAINT MONO (-2550 750);
DISPLAY INVISIBLE (-2550 750);
FORCEADD TAP..7
(-2500 275);
FORCEPROP 3 LASTPIN (-2500 325) SIG_NAME P3E_CPU0_PE1_SS_RXP<3>
J 0
(-2490 335);
DISPLAY 0.659574 (-2490 335);
PAINT MONO (-2490 335);
DISPLAY INVISIBLE (-2490 335);
FORCEPROP 1 LASTPIN (-2500 325) BN 3
R 1
J 0
(-2507 273);
DISPLAY 0.617021 (-2507 273);
PAINT GREEN (-2507 273);
FORCEPROP 2 LAST CDS_LIB mstr_standard
J 0
(-2500 275);
PAINT ORANGE (-2500 275);
DISPLAY INVISIBLE (-2500 275);
FORCEPROP 1 LAST PATH I280
J 0
(-2502 275);
DISPLAY 0.872340 (-2502 275);
PAINT GREEN (-2502 275);
DISPLAY INVISIBLE (-2502 275);
FORCEPROP 1 LAST BODY_TYPE PLUMBING
J 0
(-2450 275);
DISPLAY 2.276596 (-2450 275);
PAINT GREEN (-2450 275);
DISPLAY INVISIBLE (-2450 275);
FORCEPROP 1 LAST HDL_TAP TRUE
J 0
(-2180 145);
DISPLAY 2.276596 (-2180 145);
PAINT GREEN (-2180 145);
DISPLAY INVISIBLE (-2180 145);
FORCEADD TAP..7
(-2700 275);
FORCEPROP 3 LASTPIN (-2700 325) SIG_NAME P3E_CPU0_PE1_SS_RXP<4>
J 0
(-2690 335);
DISPLAY 0.659574 (-2690 335);
PAINT MONO (-2690 335);
DISPLAY INVISIBLE (-2690 335);
FORCEPROP 1 LASTPIN (-2700 325) BN 4
R 1
J 0
(-2707 273);
DISPLAY 0.617021 (-2707 273);
PAINT GREEN (-2707 273);
FORCEPROP 2 LAST CDS_LIB mstr_standard
J 0
(-2700 275);
PAINT ORANGE (-2700 275);
DISPLAY INVISIBLE (-2700 275);
FORCEPROP 1 LAST PATH I281
J 0
(-2702 275);
DISPLAY 0.872340 (-2702 275);
PAINT GREEN (-2702 275);
DISPLAY INVISIBLE (-2702 275);
FORCEPROP 1 LAST BODY_TYPE PLUMBING
J 0
(-2650 275);
DISPLAY 2.276596 (-2650 275);
PAINT GREEN (-2650 275);
DISPLAY INVISIBLE (-2650 275);
FORCEPROP 1 LAST HDL_TAP TRUE
J 0
(-2380 145);
DISPLAY 2.276596 (-2380 145);
PAINT GREEN (-2380 145);
DISPLAY INVISIBLE (-2380 145);
FORCEADD TAP..3
(-2950 2075);
FORCEPROP 3 LASTPIN (-2950 2025) SIG_NAME P3E_CPU0_PE1_PCH_RXN<5>
J 0
(-2940 2035);
DISPLAY 0.659574 (-2940 2035);
PAINT MONO (-2940 2035);
DISPLAY INVISIBLE (-2940 2035);
FORCEPROP 1 LASTPIN (-2950 2025) BN 5
R 1
J 0
(-2957 2013);
DISPLAY 0.617021 (-2957 2013);
PAINT GREEN (-2957 2013);
FORCEPROP 2 LAST CDS_LIB mstr_standard
J 0
(-2950 2075);
PAINT ORANGE (-2950 2075);
DISPLAY INVISIBLE (-2950 2075);
FORCEPROP 1 LAST PATH I282
J 0
(-2952 2075);
DISPLAY 0.872340 (-2952 2075);
PAINT GREEN (-2952 2075);
DISPLAY INVISIBLE (-2952 2075);
FORCEPROP 1 LAST BODY_TYPE PLUMBING
J 0
(-2900 2025);
DISPLAY 2.276596 (-2900 2025);
PAINT GREEN (-2900 2025);
DISPLAY INVISIBLE (-2900 2025);
FORCEPROP 1 LAST HDL_TAP TRUE
J 0
(-2630 1945);
DISPLAY 2.276596 (-2630 1945);
PAINT GREEN (-2630 1945);
DISPLAY INVISIBLE (-2630 1945);
FORCEADD TAP..3
(-3150 2075);
FORCEPROP 3 LASTPIN (-3150 2025) SIG_NAME P3E_CPU0_PE1_PCH_RXN<6>
J 0
(-3140 2035);
DISPLAY 0.659574 (-3140 2035);
PAINT MONO (-3140 2035);
DISPLAY INVISIBLE (-3140 2035);
FORCEPROP 1 LASTPIN (-3150 2025) BN 6
R 1
J 0
(-3157 2013);
DISPLAY 0.617021 (-3157 2013);
PAINT GREEN (-3157 2013);
FORCEPROP 2 LAST CDS_LIB mstr_standard
J 0
(-3150 2075);
PAINT ORANGE (-3150 2075);
DISPLAY INVISIBLE (-3150 2075);
FORCEPROP 1 LAST PATH I283
J 0
(-3152 2075);
DISPLAY 0.872340 (-3152 2075);
PAINT GREEN (-3152 2075);
DISPLAY INVISIBLE (-3152 2075);
FORCEPROP 1 LAST BODY_TYPE PLUMBING
J 0
(-3100 2025);
DISPLAY 2.276596 (-3100 2025);
PAINT GREEN (-3100 2025);
DISPLAY INVISIBLE (-3100 2025);
FORCEPROP 1 LAST HDL_TAP TRUE
J 0
(-2830 1945);
DISPLAY 2.276596 (-2830 1945);
PAINT GREEN (-2830 1945);
DISPLAY INVISIBLE (-2830 1945);
FORCEADD TAP..3
(-3350 2075);
FORCEPROP 3 LASTPIN (-3350 2025) SIG_NAME P3E_CPU0_PE1_PCH_RXN<7>
J 0
(-3340 2035);
DISPLAY 0.659574 (-3340 2035);
PAINT MONO (-3340 2035);
DISPLAY INVISIBLE (-3340 2035);
FORCEPROP 1 LASTPIN (-3350 2025) BN 7
R 1
J 0
(-3357 2013);
DISPLAY 0.617021 (-3357 2013);
PAINT GREEN (-3357 2013);
FORCEPROP 2 LAST CDS_LIB mstr_standard
J 0
(-3350 2075);
PAINT ORANGE (-3350 2075);
DISPLAY INVISIBLE (-3350 2075);
FORCEPROP 1 LAST PATH I284
J 0
(-3352 2075);
DISPLAY 0.872340 (-3352 2075);
PAINT GREEN (-3352 2075);
DISPLAY INVISIBLE (-3352 2075);
FORCEPROP 1 LAST BODY_TYPE PLUMBING
J 0
(-3300 2025);
DISPLAY 2.276596 (-3300 2025);
PAINT GREEN (-3300 2025);
DISPLAY INVISIBLE (-3300 2025);
FORCEPROP 1 LAST HDL_TAP TRUE
J 0
(-3030 1945);
DISPLAY 2.276596 (-3030 1945);
PAINT GREEN (-3030 1945);
DISPLAY INVISIBLE (-3030 1945);
FORCEADD OFFPAGE..1
(-3525 2125);
FORCEPROP 2 LAST $XR0 117 
J 0
(-3807 2125);
DISPLAY 0.638298 (-3807 2125);
PAINT MONO (-3807 2125);
FORCEPROP 2 LAST PATH I285
J 0
(-3475 2200);
DISPLAY 1.021277 (-3475 2200);
PAINT ORANGE (-3475 2200);
DISPLAY INVISIBLE (-3475 2200);
FORCEPROP 2 LAST CDS_LIB mstr_standard
J 0
(-3525 2125);
PAINT ORANGE (-3525 2125);
DISPLAY INVISIBLE (-3525 2125);
FORCEPROP 1 LAST OFFPAGE TRUE
J 0
(-3205 1995);
PAINT GREEN (-3205 1995);
DISPLAY INVISIBLE (-3205 1995);
FORCEPROP 1 LAST COMMENT_BODY TRUE
J 0
(-3405 2025);
DISPLAY 2.276596 (-3405 2025);
PAINT GREEN (-3405 2025);
DISPLAY INVISIBLE (-3405 2025);
FORCEADD CAP..1
R 2
(-3150 1875);
FORCEPROP 0 LAST GROUP PCIE_UPLINK
J 0
(-3307 2070);
DISPLAY 0.638298 (-3307 2070);
PAINT BROWN (-3307 2070);
DISPLAY BOTH (-3307 2070);
FORCEPROP 1 LAST PACK_TYPE 0402
J 2
(-3200 1725);
DISPLAY 0.617021 (-3200 1725);
PAINT SKYBLUE (-3200 1725);
FORCEPROP 1 LAST TOLERANCE 10%
J 2
(-3200 1825);
DISPLAY 0.617021 (-3200 1825);
PAINT SKYBLUE (-3200 1825);
FORCEPROP 1 LAST VOLTAGE 16V
J 2
(-3200 1875);
DISPLAY 0.617021 (-3200 1875);
PAINT SKYBLUE (-3200 1875);
FORCEPROP 1 LAST MATERIAL X7R
J 2
(-3200 1775);
DISPLAY 0.617021 (-3200 1775);
PAINT SKYBLUE (-3200 1775);
FORCEPROP 1 LAST LOCATION C2U16
J 2
(-3200 1975);
DISPLAY 0.617021 (-3200 1975);
PAINT AQUA (-3200 1975);
FORCEPROP 1 LASTPIN (-3150 1975) $PN 1
J 2
(-3155 1937);
DISPLAY 0.617021 (-3155 1937);
PAINT ORANGE (-3155 1937);
FORCEPROP 1 LASTPIN (-3150 1775) $PN 2
J 2
(-3155 1785);
DISPLAY 0.617021 (-3155 1785);
PAINT ORANGE (-3155 1785);
FORCEPROP 1 LAST VALUE 0.22UF
J 2
(-3200 1925);
DISPLAY 0.617021 (-3200 1925);
PAINT SKYBLUE (-3200 1925);
FORCEPROP 1 LAST PART_NUMBER A36096-155
R 1
J 2
(-3075 2000);
DISPLAY 0.617021 (-3075 2000);
PAINT BLUE (-3075 2000);
FORCEPROP 2 LAST SEC 1
J 0
(-3200 2100);
DISPLAY 0.680851 (-3200 2100);
PAINT MONO (-3200 2100);
DISPLAY INVISIBLE (-3200 2100);
FORCEPROP 2 LAST SEC_TYPE 0402
J 0
(-3200 2075);
DISPLAY 1.021277 (-3200 2075);
PAINT ORANGE (-3200 2075);
DISPLAY INVISIBLE (-3200 2075);
FORCEPROP 2 LAST CDS_LIB mstr_discrete
J 0
(-3150 1875);
PAINT MONO (-3150 1875);
DISPLAY INVISIBLE (-3150 1875);
FORCEPROP 2 LAST CDS_LOCATION C2U16
J 0
(-3200 2025);
DISPLAY 0.617021 (-3200 2025);
PAINT AQUA (-3200 2025);
DISPLAY INVISIBLE (-3200 2025);
FORCEPROP 1 LAST PATH I286
J 2
(-3200 2025);
DISPLAY 0.978723 (-3200 2025);
PAINT WHITE (-3200 2025);
DISPLAY INVISIBLE (-3200 2025);
FORCEADD CAP..1
R 2
(-2950 1525);
FORCEPROP 0 LAST GROUP PCIE_UPLINK
J 0
(-3107 1245);
DISPLAY 0.638298 (-3107 1245);
PAINT BROWN (-3107 1245);
DISPLAY BOTH (-3107 1245);
FORCEPROP 1 LAST MATERIAL X7R
J 2
(-3000 1425);
DISPLAY 0.617021 (-3000 1425);
PAINT SKYBLUE (-3000 1425);
FORCEPROP 1 LAST PART_NUMBER A36096-155
R 1
J 2
(-2875 1650);
DISPLAY 0.617021 (-2875 1650);
PAINT BLUE (-2875 1650);
FORCEPROP 1 LAST LOCATION C2U14
J 2
(-3000 1625);
DISPLAY 0.617021 (-3000 1625);
PAINT AQUA (-3000 1625);
FORCEPROP 1 LAST VOLTAGE 16V
J 2
(-3000 1525);
DISPLAY 0.617021 (-3000 1525);
PAINT SKYBLUE (-3000 1525);
FORCEPROP 1 LAST VALUE 0.22UF
J 2
(-3000 1575);
DISPLAY 0.617021 (-3000 1575);
PAINT SKYBLUE (-3000 1575);
FORCEPROP 1 LASTPIN (-2950 1425) $PN 2
J 2
(-2955 1435);
DISPLAY 0.617021 (-2955 1435);
PAINT ORANGE (-2955 1435);
FORCEPROP 1 LASTPIN (-2950 1625) $PN 1
J 2
(-2955 1587);
DISPLAY 0.617021 (-2955 1587);
PAINT ORANGE (-2955 1587);
FORCEPROP 1 LAST PACK_TYPE 0402
J 2
(-3000 1375);
DISPLAY 0.617021 (-3000 1375);
PAINT SKYBLUE (-3000 1375);
FORCEPROP 1 LAST TOLERANCE 10%
J 2
(-3000 1475);
DISPLAY 0.617021 (-3000 1475);
PAINT SKYBLUE (-3000 1475);
FORCEPROP 2 LAST CDS_LIB mstr_discrete
J 0
(-2950 1525);
PAINT MONO (-2950 1525);
DISPLAY INVISIBLE (-2950 1525);
FORCEPROP 1 LAST PATH I287
J 2
(-3000 1675);
DISPLAY 0.978723 (-3000 1675);
PAINT WHITE (-3000 1675);
DISPLAY INVISIBLE (-3000 1675);
FORCEPROP 2 LAST CDS_LOCATION C2U14
J 0
(-3000 1675);
DISPLAY 0.617021 (-3000 1675);
PAINT AQUA (-3000 1675);
DISPLAY INVISIBLE (-3000 1675);
FORCEPROP 2 LAST SEC 1
J 0
(-3000 1750);
DISPLAY 0.680851 (-3000 1750);
PAINT MONO (-3000 1750);
DISPLAY INVISIBLE (-3000 1750);
FORCEPROP 2 LAST SEC_TYPE 0402
J 0
(-3000 1725);
DISPLAY 1.021277 (-3000 1725);
PAINT ORANGE (-3000 1725);
DISPLAY INVISIBLE (-3000 1725);
FORCEADD TAP..3
(-2900 1075);
FORCEPROP 3 LASTPIN (-2900 1025) SIG_NAME P3E_CPU0_PE1_PCH_RXP<5>
J 0
(-2890 1035);
DISPLAY 0.659574 (-2890 1035);
PAINT MONO (-2890 1035);
DISPLAY INVISIBLE (-2890 1035);
FORCEPROP 1 LASTPIN (-2900 1025) BN 5
R 1
J 0
(-2907 1013);
DISPLAY 0.617021 (-2907 1013);
PAINT GREEN (-2907 1013);
FORCEPROP 1 LAST PATH I288
J 0
(-2902 1075);
DISPLAY 0.872340 (-2902 1075);
PAINT GREEN (-2902 1075);
DISPLAY INVISIBLE (-2902 1075);
FORCEPROP 2 LAST CDS_LIB mstr_standard
J 0
(-2900 1075);
PAINT ORANGE (-2900 1075);
DISPLAY INVISIBLE (-2900 1075);
FORCEPROP 1 LAST BODY_TYPE PLUMBING
J 0
(-2850 1025);
DISPLAY 2.276596 (-2850 1025);
PAINT GREEN (-2850 1025);
DISPLAY INVISIBLE (-2850 1025);
FORCEPROP 1 LAST HDL_TAP TRUE
J 0
(-2580 945);
DISPLAY 2.276596 (-2580 945);
PAINT GREEN (-2580 945);
DISPLAY INVISIBLE (-2580 945);
FORCEADD TAP..7
(-2950 1275);
FORCEPROP 3 LASTPIN (-2950 1325) SIG_NAME P3E_CPU0_PE1_SS_RXN<5>
J 0
(-2940 1335);
DISPLAY 0.659574 (-2940 1335);
PAINT MONO (-2940 1335);
DISPLAY INVISIBLE (-2940 1335);
FORCEPROP 1 LASTPIN (-2950 1325) BN 5
R 1
J 0
(-2957 1273);
DISPLAY 0.617021 (-2957 1273);
PAINT GREEN (-2957 1273);
FORCEPROP 2 LAST CDS_LIB mstr_standard
J 0
(-2950 1275);
PAINT ORANGE (-2950 1275);
DISPLAY INVISIBLE (-2950 1275);
FORCEPROP 1 LAST PATH I289
J 0
(-2952 1275);
DISPLAY 0.872340 (-2952 1275);
PAINT GREEN (-2952 1275);
DISPLAY INVISIBLE (-2952 1275);
FORCEPROP 1 LAST BODY_TYPE PLUMBING
J 0
(-2900 1275);
DISPLAY 2.276596 (-2900 1275);
PAINT GREEN (-2900 1275);
DISPLAY INVISIBLE (-2900 1275);
FORCEPROP 1 LAST HDL_TAP TRUE
J 0
(-2630 1145);
DISPLAY 2.276596 (-2630 1145);
PAINT GREEN (-2630 1145);
DISPLAY INVISIBLE (-2630 1145);
FORCEADD TAP..7
(-3150 1275);
FORCEPROP 3 LASTPIN (-3150 1325) SIG_NAME P3E_CPU0_PE1_SS_RXN<6>
J 0
(-3140 1335);
DISPLAY 0.659574 (-3140 1335);
PAINT MONO (-3140 1335);
DISPLAY INVISIBLE (-3140 1335);
FORCEPROP 1 LASTPIN (-3150 1325) BN 6
R 1
J 0
(-3157 1273);
DISPLAY 0.617021 (-3157 1273);
PAINT GREEN (-3157 1273);
FORCEPROP 2 LAST CDS_LIB mstr_standard
J 0
(-3150 1275);
PAINT ORANGE (-3150 1275);
DISPLAY INVISIBLE (-3150 1275);
FORCEPROP 1 LAST PATH I290
J 0
(-3152 1275);
DISPLAY 0.872340 (-3152 1275);
PAINT GREEN (-3152 1275);
DISPLAY INVISIBLE (-3152 1275);
FORCEPROP 1 LAST BODY_TYPE PLUMBING
J 0
(-3100 1275);
DISPLAY 2.276596 (-3100 1275);
PAINT GREEN (-3100 1275);
DISPLAY INVISIBLE (-3100 1275);
FORCEPROP 1 LAST HDL_TAP TRUE
J 0
(-2830 1145);
DISPLAY 2.276596 (-2830 1145);
PAINT GREEN (-2830 1145);
DISPLAY INVISIBLE (-2830 1145);
FORCEADD TAP..3
(-3100 1075);
FORCEPROP 3 LASTPIN (-3100 1025) SIG_NAME P3E_CPU0_PE1_PCH_RXP<6>
J 0
(-3090 1035);
DISPLAY 0.659574 (-3090 1035);
PAINT MONO (-3090 1035);
DISPLAY INVISIBLE (-3090 1035);
FORCEPROP 1 LASTPIN (-3100 1025) BN 6
R 1
J 0
(-3107 1013);
DISPLAY 0.617021 (-3107 1013);
PAINT GREEN (-3107 1013);
FORCEPROP 1 LAST PATH I291
J 0
(-3102 1075);
DISPLAY 0.872340 (-3102 1075);
PAINT GREEN (-3102 1075);
DISPLAY INVISIBLE (-3102 1075);
FORCEPROP 2 LAST CDS_LIB mstr_standard
J 0
(-3100 1075);
PAINT ORANGE (-3100 1075);
DISPLAY INVISIBLE (-3100 1075);
FORCEPROP 1 LAST BODY_TYPE PLUMBING
J 0
(-3050 1025);
DISPLAY 2.276596 (-3050 1025);
PAINT GREEN (-3050 1025);
DISPLAY INVISIBLE (-3050 1025);
FORCEPROP 1 LAST HDL_TAP TRUE
J 0
(-2780 945);
DISPLAY 2.276596 (-2780 945);
PAINT GREEN (-2780 945);
DISPLAY INVISIBLE (-2780 945);
FORCEADD TAP..7
(-3350 1275);
FORCEPROP 3 LASTPIN (-3350 1325) SIG_NAME P3E_CPU0_PE1_SS_RXN<7>
J 0
(-3340 1335);
DISPLAY 0.659574 (-3340 1335);
PAINT MONO (-3340 1335);
DISPLAY INVISIBLE (-3340 1335);
FORCEPROP 1 LASTPIN (-3350 1325) BN 7
R 1
J 0
(-3357 1273);
DISPLAY 0.617021 (-3357 1273);
PAINT GREEN (-3357 1273);
FORCEPROP 2 LAST CDS_LIB mstr_standard
J 0
(-3350 1275);
PAINT ORANGE (-3350 1275);
DISPLAY INVISIBLE (-3350 1275);
FORCEPROP 1 LAST PATH I292
J 0
(-3352 1275);
DISPLAY 0.872340 (-3352 1275);
PAINT GREEN (-3352 1275);
DISPLAY INVISIBLE (-3352 1275);
FORCEPROP 1 LAST BODY_TYPE PLUMBING
J 0
(-3300 1275);
DISPLAY 2.276596 (-3300 1275);
PAINT GREEN (-3300 1275);
DISPLAY INVISIBLE (-3300 1275);
FORCEPROP 1 LAST HDL_TAP TRUE
J 0
(-3030 1145);
DISPLAY 2.276596 (-3030 1145);
PAINT GREEN (-3030 1145);
DISPLAY INVISIBLE (-3030 1145);
FORCEADD TAP..3
(-3300 1075);
FORCEPROP 3 LASTPIN (-3300 1025) SIG_NAME P3E_CPU0_PE1_PCH_RXP<7>
J 0
(-3290 1035);
DISPLAY 0.659574 (-3290 1035);
PAINT MONO (-3290 1035);
DISPLAY INVISIBLE (-3290 1035);
FORCEPROP 1 LASTPIN (-3300 1025) BN 7
R 1
J 0
(-3307 1013);
DISPLAY 0.617021 (-3307 1013);
PAINT GREEN (-3307 1013);
FORCEPROP 2 LAST CDS_LIB mstr_standard
J 0
(-3300 1075);
PAINT ORANGE (-3300 1075);
DISPLAY INVISIBLE (-3300 1075);
FORCEPROP 1 LAST PATH I293
J 0
(-3302 1075);
DISPLAY 0.872340 (-3302 1075);
PAINT GREEN (-3302 1075);
DISPLAY INVISIBLE (-3302 1075);
FORCEPROP 1 LAST BODY_TYPE PLUMBING
J 0
(-3250 1025);
DISPLAY 2.276596 (-3250 1025);
PAINT GREEN (-3250 1025);
DISPLAY INVISIBLE (-3250 1025);
FORCEPROP 1 LAST HDL_TAP TRUE
J 0
(-2980 945);
DISPLAY 2.276596 (-2980 945);
PAINT GREEN (-2980 945);
DISPLAY INVISIBLE (-2980 945);
FORCEADD CAP..1
R 2
(-3350 1525);
FORCEPROP 0 LAST GROUP PCIE_UPLINK
J 0
(-3582 1245);
DISPLAY 0.638298 (-3582 1245);
PAINT BROWN (-3582 1245);
DISPLAY BOTH (-3582 1245);
FORCEPROP 1 LAST PART_NUMBER A36096-155
J 2
(-3400 1375);
DISPLAY 0.617021 (-3400 1375);
PAINT BLUE (-3400 1375);
FORCEPROP 1 LAST VALUE 0.22UF
J 2
(-3400 1575);
DISPLAY 0.617021 (-3400 1575);
PAINT SKYBLUE (-3400 1575);
FORCEPROP 1 LAST PACK_TYPE 0402
J 2
(-3400 1325);
DISPLAY 0.617021 (-3400 1325);
PAINT SKYBLUE (-3400 1325);
FORCEPROP 1 LAST MATERIAL X7R
J 2
(-3400 1425);
DISPLAY 0.617021 (-3400 1425);
PAINT SKYBLUE (-3400 1425);
FORCEPROP 1 LASTPIN (-3350 1425) $PN 2
J 2
(-3355 1435);
DISPLAY 0.617021 (-3355 1435);
PAINT ORANGE (-3355 1435);
FORCEPROP 1 LASTPIN (-3350 1625) $PN 1
J 2
(-3355 1587);
DISPLAY 0.617021 (-3355 1587);
PAINT ORANGE (-3355 1587);
FORCEPROP 1 LAST TOLERANCE 10%
J 2
(-3400 1475);
DISPLAY 0.617021 (-3400 1475);
PAINT SKYBLUE (-3400 1475);
FORCEPROP 1 LAST VOLTAGE 16V
J 2
(-3400 1525);
DISPLAY 0.617021 (-3400 1525);
PAINT SKYBLUE (-3400 1525);
FORCEPROP 1 LAST LOCATION C2U18
J 2
(-3400 1625);
DISPLAY 0.617021 (-3400 1625);
PAINT AQUA (-3400 1625);
FORCEPROP 2 LAST CDS_LIB mstr_discrete
J 0
(-3350 1525);
PAINT MONO (-3350 1525);
DISPLAY INVISIBLE (-3350 1525);
FORCEPROP 1 LAST PATH I294
J 2
(-3400 1675);
DISPLAY 0.978723 (-3400 1675);
PAINT WHITE (-3400 1675);
DISPLAY INVISIBLE (-3400 1675);
FORCEPROP 2 LAST CDS_LOCATION C2U18
J 0
(-3400 1675);
DISPLAY 0.617021 (-3400 1675);
PAINT AQUA (-3400 1675);
DISPLAY INVISIBLE (-3400 1675);
FORCEPROP 2 LAST SEC_TYPE 0402
J 0
(-3400 1725);
DISPLAY 1.021277 (-3400 1725);
PAINT ORANGE (-3400 1725);
DISPLAY INVISIBLE (-3400 1725);
FORCEPROP 2 LAST SEC 1
J 0
(-3400 1750);
DISPLAY 0.680851 (-3400 1750);
PAINT MONO (-3400 1750);
DISPLAY INVISIBLE (-3400 1750);
FORCEADD OFFPAGE..1
(-3475 1125);
FORCEPROP 2 LAST $XR0 117 
J 0
(-3727 1125);
DISPLAY 0.638298 (-3727 1125);
PAINT MONO (-3727 1125);
FORCEPROP 2 LAST PATH I295
J 0
(-3425 1200);
DISPLAY 1.021277 (-3425 1200);
PAINT ORANGE (-3425 1200);
DISPLAY INVISIBLE (-3425 1200);
FORCEPROP 2 LAST CDS_LIB mstr_standard
J 0
(-3475 1125);
PAINT ORANGE (-3475 1125);
DISPLAY INVISIBLE (-3475 1125);
FORCEPROP 1 LAST OFFPAGE TRUE
J 0
(-3155 995);
PAINT GREEN (-3155 995);
DISPLAY INVISIBLE (-3155 995);
FORCEPROP 1 LAST COMMENT_BODY TRUE
J 0
(-3355 1025);
DISPLAY 2.276596 (-3355 1025);
PAINT GREEN (-3355 1025);
DISPLAY INVISIBLE (-3355 1025);
FORCEADD CAP..1
R 2
(-3100 875);
FORCEPROP 1 LAST PART_NUMBER A36096-155
R 1
J 2
(-3025 1000);
DISPLAY 0.617021 (-3025 1000);
PAINT BLUE (-3025 1000);
FORCEPROP 1 LAST LOCATION C2U15
J 2
(-3150 975);
DISPLAY 0.617021 (-3150 975);
PAINT AQUA (-3150 975);
FORCEPROP 1 LAST PACK_TYPE 0402
J 2
(-3150 725);
DISPLAY 0.617021 (-3150 725);
PAINT SKYBLUE (-3150 725);
FORCEPROP 1 LASTPIN (-3100 975) $PN 1
J 2
(-3105 937);
DISPLAY 0.617021 (-3105 937);
PAINT ORANGE (-3105 937);
FORCEPROP 1 LAST TOLERANCE 10%
J 2
(-3150 825);
DISPLAY 0.617021 (-3150 825);
PAINT SKYBLUE (-3150 825);
FORCEPROP 1 LAST VOLTAGE 16V
J 2
(-3150 875);
DISPLAY 0.617021 (-3150 875);
PAINT SKYBLUE (-3150 875);
FORCEPROP 1 LAST VALUE 0.22UF
J 2
(-3150 925);
DISPLAY 0.617021 (-3150 925);
PAINT SKYBLUE (-3150 925);
FORCEPROP 1 LASTPIN (-3100 775) $PN 2
J 2
(-3105 785);
DISPLAY 0.617021 (-3105 785);
PAINT ORANGE (-3105 785);
FORCEPROP 1 LAST MATERIAL X7R
J 2
(-3150 775);
DISPLAY 0.617021 (-3150 775);
PAINT SKYBLUE (-3150 775);
FORCEPROP 0 LAST GROUP PCIE_UPLINK
J 0
(-3257 1070);
DISPLAY 0.638298 (-3257 1070);
PAINT BROWN (-3257 1070);
DISPLAY BOTH (-3257 1070);
FORCEPROP 2 LAST SEC_TYPE 0402
J 0
(-3150 1075);
DISPLAY 1.021277 (-3150 1075);
PAINT ORANGE (-3150 1075);
DISPLAY INVISIBLE (-3150 1075);
FORCEPROP 2 LAST SEC 1
J 0
(-3150 1100);
DISPLAY 0.680851 (-3150 1100);
PAINT MONO (-3150 1100);
DISPLAY INVISIBLE (-3150 1100);
FORCEPROP 2 LAST CDS_LOCATION C2U15
J 0
(-3150 1025);
DISPLAY 0.617021 (-3150 1025);
PAINT AQUA (-3150 1025);
DISPLAY INVISIBLE (-3150 1025);
FORCEPROP 2 LAST CDS_LIB mstr_discrete
J 0
(-3100 875);
PAINT MONO (-3100 875);
DISPLAY INVISIBLE (-3100 875);
FORCEPROP 1 LAST PATH I296
J 2
(-3150 1025);
DISPLAY 0.978723 (-3150 1025);
PAINT WHITE (-3150 1025);
DISPLAY INVISIBLE (-3150 1025);
FORCEADD CAP..1
R 2
(-2900 525);
FORCEPROP 1 LAST PACK_TYPE 0402
J 2
(-2950 375);
DISPLAY 0.617021 (-2950 375);
PAINT SKYBLUE (-2950 375);
FORCEPROP 1 LAST MATERIAL X7R
J 2
(-2950 425);
DISPLAY 0.617021 (-2950 425);
PAINT SKYBLUE (-2950 425);
FORCEPROP 1 LAST TOLERANCE 10%
J 2
(-2950 475);
DISPLAY 0.617021 (-2950 475);
PAINT SKYBLUE (-2950 475);
FORCEPROP 1 LAST VOLTAGE 16V
J 2
(-2950 525);
DISPLAY 0.617021 (-2950 525);
PAINT SKYBLUE (-2950 525);
FORCEPROP 1 LAST VALUE 0.22UF
J 2
(-2950 575);
DISPLAY 0.617021 (-2950 575);
PAINT SKYBLUE (-2950 575);
FORCEPROP 1 LAST LOCATION C2U13
J 2
(-2950 625);
DISPLAY 0.617021 (-2950 625);
PAINT AQUA (-2950 625);
FORCEPROP 1 LASTPIN (-2900 625) $PN 1
J 2
(-2905 587);
DISPLAY 0.617021 (-2905 587);
PAINT ORANGE (-2905 587);
FORCEPROP 1 LASTPIN (-2900 425) $PN 2
J 2
(-2905 435);
DISPLAY 0.617021 (-2905 435);
PAINT ORANGE (-2905 435);
FORCEPROP 1 LAST PART_NUMBER A36096-155
R 1
J 2
(-2825 625);
DISPLAY 0.617021 (-2825 625);
PAINT BLUE (-2825 625);
FORCEPROP 0 LAST GROUP PCIE_UPLINK
J 0
(-3057 320);
DISPLAY 0.638298 (-3057 320);
PAINT BROWN (-3057 320);
DISPLAY BOTH (-3057 320);
FORCEPROP 1 LAST PATH I297
J 2
(-2950 675);
DISPLAY 0.978723 (-2950 675);
PAINT WHITE (-2950 675);
DISPLAY INVISIBLE (-2950 675);
FORCEPROP 2 LAST SEC 1
J 0
(-2950 750);
DISPLAY 0.680851 (-2950 750);
PAINT MONO (-2950 750);
DISPLAY INVISIBLE (-2950 750);
FORCEPROP 2 LAST SEC_TYPE 0402
J 0
(-2950 725);
DISPLAY 1.021277 (-2950 725);
PAINT ORANGE (-2950 725);
DISPLAY INVISIBLE (-2950 725);
FORCEPROP 2 LAST CDS_LIB mstr_discrete
J 0
(-2900 525);
PAINT MONO (-2900 525);
DISPLAY INVISIBLE (-2900 525);
FORCEPROP 2 LAST CDS_LOCATION C2U13
J 0
(-2950 675);
DISPLAY 0.617021 (-2950 675);
PAINT AQUA (-2950 675);
DISPLAY INVISIBLE (-2950 675);
FORCEADD TAP..7
(-2900 275);
FORCEPROP 3 LASTPIN (-2900 325) SIG_NAME P3E_CPU0_PE1_SS_RXP<5>
J 0
(-2890 335);
DISPLAY 0.659574 (-2890 335);
PAINT MONO (-2890 335);
DISPLAY INVISIBLE (-2890 335);
FORCEPROP 1 LASTPIN (-2900 325) BN 5
R 1
J 0
(-2907 273);
DISPLAY 0.617021 (-2907 273);
PAINT GREEN (-2907 273);
FORCEPROP 2 LAST CDS_LIB mstr_standard
J 0
(-2900 275);
PAINT ORANGE (-2900 275);
DISPLAY INVISIBLE (-2900 275);
FORCEPROP 1 LAST PATH I298
J 0
(-2902 275);
DISPLAY 0.872340 (-2902 275);
PAINT GREEN (-2902 275);
DISPLAY INVISIBLE (-2902 275);
FORCEPROP 1 LAST BODY_TYPE PLUMBING
J 0
(-2850 275);
DISPLAY 2.276596 (-2850 275);
PAINT GREEN (-2850 275);
DISPLAY INVISIBLE (-2850 275);
FORCEPROP 1 LAST HDL_TAP TRUE
J 0
(-2580 145);
DISPLAY 2.276596 (-2580 145);
PAINT GREEN (-2580 145);
DISPLAY INVISIBLE (-2580 145);
FORCEADD TAP..7
(-3100 275);
FORCEPROP 3 LASTPIN (-3100 325) SIG_NAME P3E_CPU0_PE1_SS_RXP<6>
J 0
(-3090 335);
DISPLAY 0.659574 (-3090 335);
PAINT MONO (-3090 335);
DISPLAY INVISIBLE (-3090 335);
FORCEPROP 1 LASTPIN (-3100 325) BN 6
R 1
J 0
(-3107 273);
DISPLAY 0.617021 (-3107 273);
PAINT GREEN (-3107 273);
FORCEPROP 2 LAST CDS_LIB mstr_standard
J 0
(-3100 275);
PAINT ORANGE (-3100 275);
DISPLAY INVISIBLE (-3100 275);
FORCEPROP 1 LAST PATH I299
J 0
(-3102 275);
DISPLAY 0.872340 (-3102 275);
PAINT GREEN (-3102 275);
DISPLAY INVISIBLE (-3102 275);
FORCEPROP 1 LAST BODY_TYPE PLUMBING
J 0
(-3050 275);
DISPLAY 2.276596 (-3050 275);
PAINT GREEN (-3050 275);
DISPLAY INVISIBLE (-3050 275);
FORCEPROP 1 LAST HDL_TAP TRUE
J 0
(-2780 145);
DISPLAY 2.276596 (-2780 145);
PAINT GREEN (-2780 145);
DISPLAY INVISIBLE (-2780 145);
FORCEADD CAP..1
R 2
(-3300 525);
FORCEPROP 1 LAST MATERIAL X7R
J 2
(-3350 425);
DISPLAY 0.617021 (-3350 425);
PAINT SKYBLUE (-3350 425);
FORCEPROP 1 LAST PACK_TYPE 0402
J 2
(-3350 375);
DISPLAY 0.617021 (-3350 375);
PAINT SKYBLUE (-3350 375);
FORCEPROP 1 LASTPIN (-3300 625) $PN 1
J 2
(-3305 587);
DISPLAY 0.617021 (-3305 587);
PAINT ORANGE (-3305 587);
FORCEPROP 1 LAST VALUE 0.22UF
J 2
(-3350 575);
DISPLAY 0.617021 (-3350 575);
PAINT SKYBLUE (-3350 575);
FORCEPROP 1 LAST LOCATION C2U17
J 2
(-3350 625);
DISPLAY 0.617021 (-3350 625);
PAINT AQUA (-3350 625);
FORCEPROP 1 LAST PART_NUMBER A36096-155
R 1
J 2
(-3225 625);
DISPLAY 0.617021 (-3225 625);
PAINT BLUE (-3225 625);
FORCEPROP 1 LASTPIN (-3300 425) $PN 2
J 2
(-3305 435);
DISPLAY 0.617021 (-3305 435);
PAINT ORANGE (-3305 435);
FORCEPROP 1 LAST TOLERANCE 10%
J 2
(-3350 475);
DISPLAY 0.617021 (-3350 475);
PAINT SKYBLUE (-3350 475);
FORCEPROP 1 LAST VOLTAGE 16V
J 2
(-3350 525);
DISPLAY 0.617021 (-3350 525);
PAINT SKYBLUE (-3350 525);
FORCEPROP 0 LAST GROUP PCIE_UPLINK
J 0
(-3507 320);
DISPLAY 0.638298 (-3507 320);
PAINT BROWN (-3507 320);
DISPLAY BOTH (-3507 320);
FORCEPROP 2 LAST CDS_LOCATION C2U17
J 0
(-3350 675);
DISPLAY 0.617021 (-3350 675);
PAINT AQUA (-3350 675);
DISPLAY INVISIBLE (-3350 675);
FORCEPROP 2 LAST SEC 1
J 0
(-3350 750);
DISPLAY 0.680851 (-3350 750);
PAINT MONO (-3350 750);
DISPLAY INVISIBLE (-3350 750);
FORCEPROP 2 LAST SEC_TYPE 0402
J 0
(-3350 725);
DISPLAY 1.021277 (-3350 725);
PAINT ORANGE (-3350 725);
DISPLAY INVISIBLE (-3350 725);
FORCEPROP 1 LAST PATH I300
J 2
(-3350 675);
DISPLAY 0.978723 (-3350 675);
PAINT WHITE (-3350 675);
DISPLAY INVISIBLE (-3350 675);
FORCEPROP 2 LAST CDS_LIB mstr_discrete
J 0
(-3300 525);
PAINT MONO (-3300 525);
DISPLAY INVISIBLE (-3300 525);
FORCEADD TAP..7
(-3300 275);
FORCEPROP 3 LASTPIN (-3300 325) SIG_NAME P3E_CPU0_PE1_SS_RXP<7>
J 0
(-3290 335);
DISPLAY 0.659574 (-3290 335);
PAINT MONO (-3290 335);
DISPLAY INVISIBLE (-3290 335);
FORCEPROP 1 LASTPIN (-3300 325) BN 7
R 1
J 0
(-3307 273);
DISPLAY 0.617021 (-3307 273);
PAINT GREEN (-3307 273);
FORCEPROP 1 LAST PATH I301
J 0
(-3302 275);
DISPLAY 0.872340 (-3302 275);
PAINT GREEN (-3302 275);
DISPLAY INVISIBLE (-3302 275);
FORCEPROP 2 LAST CDS_LIB mstr_standard
J 0
(-3300 275);
PAINT ORANGE (-3300 275);
DISPLAY INVISIBLE (-3300 275);
FORCEPROP 1 LAST BODY_TYPE PLUMBING
J 0
(-3250 275);
DISPLAY 2.276596 (-3250 275);
PAINT GREEN (-3250 275);
DISPLAY INVISIBLE (-3250 275);
FORCEPROP 1 LAST HDL_TAP TRUE
J 0
(-2980 145);
DISPLAY 2.276596 (-2980 145);
PAINT GREEN (-2980 145);
DISPLAY INVISIBLE (-2980 145);
FORCEADD TAP..3
(-825 4375);
FORCEPROP 3 LASTPIN (-825 4325) SIG_NAME P3E_CPU0_PE1_SS_R_RXN<0>
J 0
(-815 4335);
DISPLAY 0.659574 (-815 4335);
PAINT MONO (-815 4335);
DISPLAY INVISIBLE (-815 4335);
FORCEPROP 1 LASTPIN (-825 4325) BN 0
R 1
J 0
(-832 4313);
DISPLAY 0.617021 (-832 4313);
PAINT GREEN (-832 4313);
FORCEPROP 2 LAST CDS_LIB mstr_standard
J 0
(-825 4375);
PAINT MONO (-825 4375);
DISPLAY INVISIBLE (-825 4375);
FORCEPROP 1 LAST PATH I355
J 0
(-827 4375);
DISPLAY 0.872340 (-827 4375);
PAINT GREEN (-827 4375);
DISPLAY INVISIBLE (-827 4375);
FORCEPROP 1 LAST BODY_TYPE PLUMBING
J 0
(-775 4325);
DISPLAY 2.276596 (-775 4325);
PAINT GREEN (-775 4325);
DISPLAY INVISIBLE (-775 4325);
FORCEPROP 1 LAST HDL_TAP TRUE
J 0
(-505 4245);
DISPLAY 2.276596 (-505 4245);
PAINT GREEN (-505 4245);
DISPLAY INVISIBLE (-505 4245);
FORCEADD TAP..3
(-1025 4375);
FORCEPROP 3 LASTPIN (-1025 4325) SIG_NAME P3E_CPU0_PE1_SS_R_RXN<1>
J 0
(-1015 4335);
DISPLAY 0.659574 (-1015 4335);
PAINT MONO (-1015 4335);
DISPLAY INVISIBLE (-1015 4335);
FORCEPROP 1 LASTPIN (-1025 4325) BN 1
R 1
J 0
(-1032 4313);
DISPLAY 0.617021 (-1032 4313);
PAINT GREEN (-1032 4313);
FORCEPROP 2 LAST CDS_LIB mstr_standard
J 0
(-1025 4375);
PAINT MONO (-1025 4375);
DISPLAY INVISIBLE (-1025 4375);
FORCEPROP 1 LAST PATH I356
J 0
(-1027 4375);
DISPLAY 0.872340 (-1027 4375);
PAINT GREEN (-1027 4375);
DISPLAY INVISIBLE (-1027 4375);
FORCEPROP 1 LAST BODY_TYPE PLUMBING
J 0
(-975 4325);
DISPLAY 2.276596 (-975 4325);
PAINT GREEN (-975 4325);
DISPLAY INVISIBLE (-975 4325);
FORCEPROP 1 LAST HDL_TAP TRUE
J 0
(-705 4245);
DISPLAY 2.276596 (-705 4245);
PAINT GREEN (-705 4245);
DISPLAY INVISIBLE (-705 4245);
FORCEADD TAP..3
(-1225 4375);
FORCEPROP 3 LASTPIN (-1225 4325) SIG_NAME P3E_CPU0_PE1_SS_R_RXN<2>
J 0
(-1215 4335);
DISPLAY 0.659574 (-1215 4335);
PAINT MONO (-1215 4335);
DISPLAY INVISIBLE (-1215 4335);
FORCEPROP 1 LASTPIN (-1225 4325) BN 2
R 1
J 0
(-1232 4313);
DISPLAY 0.617021 (-1232 4313);
PAINT GREEN (-1232 4313);
FORCEPROP 2 LAST CDS_LIB mstr_standard
J 0
(-1225 4375);
PAINT MONO (-1225 4375);
DISPLAY INVISIBLE (-1225 4375);
FORCEPROP 1 LAST PATH I357
J 0
(-1227 4375);
DISPLAY 0.872340 (-1227 4375);
PAINT GREEN (-1227 4375);
DISPLAY INVISIBLE (-1227 4375);
FORCEPROP 1 LAST BODY_TYPE PLUMBING
J 0
(-1175 4325);
DISPLAY 2.276596 (-1175 4325);
PAINT GREEN (-1175 4325);
DISPLAY INVISIBLE (-1175 4325);
FORCEPROP 1 LAST HDL_TAP TRUE
J 0
(-905 4245);
DISPLAY 2.276596 (-905 4245);
PAINT GREEN (-905 4245);
DISPLAY INVISIBLE (-905 4245);
FORCEADD TAP..3
(-1425 4375);
FORCEPROP 3 LASTPIN (-1425 4325) SIG_NAME P3E_CPU0_PE1_SS_R_RXN<3>
J 0
(-1415 4335);
DISPLAY 0.659574 (-1415 4335);
PAINT MONO (-1415 4335);
DISPLAY INVISIBLE (-1415 4335);
FORCEPROP 1 LASTPIN (-1425 4325) BN 3
R 1
J 0
(-1432 4313);
DISPLAY 0.617021 (-1432 4313);
PAINT GREEN (-1432 4313);
FORCEPROP 2 LAST CDS_LIB mstr_standard
J 0
(-1425 4375);
PAINT MONO (-1425 4375);
DISPLAY INVISIBLE (-1425 4375);
FORCEPROP 1 LAST PATH I359
J 0
(-1427 4375);
DISPLAY 0.872340 (-1427 4375);
PAINT GREEN (-1427 4375);
DISPLAY INVISIBLE (-1427 4375);
FORCEPROP 1 LAST BODY_TYPE PLUMBING
J 0
(-1375 4325);
DISPLAY 2.276596 (-1375 4325);
PAINT GREEN (-1375 4325);
DISPLAY INVISIBLE (-1375 4325);
FORCEPROP 1 LAST HDL_TAP TRUE
J 0
(-1105 4245);
DISPLAY 2.276596 (-1105 4245);
PAINT GREEN (-1105 4245);
DISPLAY INVISIBLE (-1105 4245);
FORCEADD TAP..3
(-1625 4375);
FORCEPROP 3 LASTPIN (-1625 4325) SIG_NAME P3E_CPU0_PE1_SS_R_RXN<4>
J 0
(-1615 4335);
DISPLAY 0.659574 (-1615 4335);
PAINT MONO (-1615 4335);
DISPLAY INVISIBLE (-1615 4335);
FORCEPROP 1 LASTPIN (-1625 4325) BN 4
R 1
J 0
(-1632 4313);
DISPLAY 0.617021 (-1632 4313);
PAINT GREEN (-1632 4313);
FORCEPROP 2 LAST CDS_LIB mstr_standard
J 0
(-1625 4375);
PAINT MONO (-1625 4375);
DISPLAY INVISIBLE (-1625 4375);
FORCEPROP 1 LAST PATH I360
J 0
(-1627 4375);
DISPLAY 0.872340 (-1627 4375);
PAINT GREEN (-1627 4375);
DISPLAY INVISIBLE (-1627 4375);
FORCEPROP 1 LAST BODY_TYPE PLUMBING
J 0
(-1575 4325);
DISPLAY 2.276596 (-1575 4325);
PAINT GREEN (-1575 4325);
DISPLAY INVISIBLE (-1575 4325);
FORCEPROP 1 LAST HDL_TAP TRUE
J 0
(-1305 4245);
DISPLAY 2.276596 (-1305 4245);
PAINT GREEN (-1305 4245);
DISPLAY INVISIBLE (-1305 4245);
FORCEADD TAP..3
(-1825 4375);
FORCEPROP 3 LASTPIN (-1825 4325) SIG_NAME P3E_CPU0_PE1_SS_R_RXN<5>
J 0
(-1815 4335);
DISPLAY 0.659574 (-1815 4335);
PAINT MONO (-1815 4335);
DISPLAY INVISIBLE (-1815 4335);
FORCEPROP 1 LASTPIN (-1825 4325) BN 5
R 1
J 0
(-1832 4313);
DISPLAY 0.617021 (-1832 4313);
PAINT GREEN (-1832 4313);
FORCEPROP 2 LAST CDS_LIB mstr_standard
J 0
(-1825 4375);
PAINT MONO (-1825 4375);
DISPLAY INVISIBLE (-1825 4375);
FORCEPROP 1 LAST PATH I361
J 0
(-1827 4375);
DISPLAY 0.872340 (-1827 4375);
PAINT GREEN (-1827 4375);
DISPLAY INVISIBLE (-1827 4375);
FORCEPROP 1 LAST BODY_TYPE PLUMBING
J 0
(-1775 4325);
DISPLAY 2.276596 (-1775 4325);
PAINT GREEN (-1775 4325);
DISPLAY INVISIBLE (-1775 4325);
FORCEPROP 1 LAST HDL_TAP TRUE
J 0
(-1505 4245);
DISPLAY 2.276596 (-1505 4245);
PAINT GREEN (-1505 4245);
DISPLAY INVISIBLE (-1505 4245);
FORCEADD TAP..3
(-2025 4375);
FORCEPROP 3 LASTPIN (-2025 4325) SIG_NAME P3E_CPU0_PE1_SS_R_RXN<6>
J 0
(-2015 4335);
DISPLAY 0.659574 (-2015 4335);
PAINT MONO (-2015 4335);
DISPLAY INVISIBLE (-2015 4335);
FORCEPROP 1 LASTPIN (-2025 4325) BN 6
R 1
J 0
(-2032 4313);
DISPLAY 0.617021 (-2032 4313);
PAINT GREEN (-2032 4313);
FORCEPROP 2 LAST CDS_LIB mstr_standard
J 0
(-2025 4375);
PAINT MONO (-2025 4375);
DISPLAY INVISIBLE (-2025 4375);
FORCEPROP 1 LAST PATH I363
J 0
(-2027 4375);
DISPLAY 0.872340 (-2027 4375);
PAINT GREEN (-2027 4375);
DISPLAY INVISIBLE (-2027 4375);
FORCEPROP 1 LAST BODY_TYPE PLUMBING
J 0
(-1975 4325);
DISPLAY 2.276596 (-1975 4325);
PAINT GREEN (-1975 4325);
DISPLAY INVISIBLE (-1975 4325);
FORCEPROP 1 LAST HDL_TAP TRUE
J 0
(-1705 4245);
DISPLAY 2.276596 (-1705 4245);
PAINT GREEN (-1705 4245);
DISPLAY INVISIBLE (-1705 4245);
FORCEADD TAP..3
(-2225 4375);
FORCEPROP 3 LASTPIN (-2225 4325) SIG_NAME P3E_CPU0_PE1_SS_R_RXN<7>
J 0
(-2215 4335);
DISPLAY 0.659574 (-2215 4335);
PAINT MONO (-2215 4335);
DISPLAY INVISIBLE (-2215 4335);
FORCEPROP 1 LASTPIN (-2225 4325) BN 7
R 1
J 0
(-2232 4313);
DISPLAY 0.617021 (-2232 4313);
PAINT GREEN (-2232 4313);
FORCEPROP 2 LAST CDS_LIB mstr_standard
J 0
(-2225 4375);
PAINT MONO (-2225 4375);
DISPLAY INVISIBLE (-2225 4375);
FORCEPROP 1 LAST PATH I365
J 0
(-2227 4375);
DISPLAY 0.872340 (-2227 4375);
PAINT GREEN (-2227 4375);
DISPLAY INVISIBLE (-2227 4375);
FORCEPROP 1 LAST BODY_TYPE PLUMBING
J 0
(-2175 4325);
DISPLAY 2.276596 (-2175 4325);
PAINT GREEN (-2175 4325);
DISPLAY INVISIBLE (-2175 4325);
FORCEPROP 1 LAST HDL_TAP TRUE
J 0
(-1905 4245);
DISPLAY 2.276596 (-1905 4245);
PAINT GREEN (-1905 4245);
DISPLAY INVISIBLE (-1905 4245);
FORCEADD OFFPAGE..1
(-2500 4425);
FORCEPROP 2 LAST $XR0 109 
J 0
(-2752 4425);
DISPLAY 0.638298 (-2752 4425);
PAINT MONO (-2752 4425);
FORCEPROP 2 LAST PATH I366
J 0
(-2700 4475);
DISPLAY 1.021277 (-2700 4475);
PAINT ORANGE (-2700 4475);
DISPLAY INVISIBLE (-2700 4475);
FORCEPROP 2 LAST CDS_LIB mstr_standard
J 0
(-2500 4425);
PAINT MONO (-2500 4425);
DISPLAY INVISIBLE (-2500 4425);
FORCEPROP 1 LAST OFFPAGE TRUE
J 0
(-2180 4295);
PAINT GREEN (-2180 4295);
DISPLAY INVISIBLE (-2180 4295);
FORCEPROP 1 LAST COMMENT_BODY TRUE
J 0
(-2380 4325);
DISPLAY 2.276596 (-2380 4325);
PAINT GREEN (-2380 4325);
DISPLAY INVISIBLE (-2380 4325);
FORCEADD TAP..7
(-825 3575);
FORCEPROP 3 LASTPIN (-825 3625) SIG_NAME P3E_CPU0_PE1_SS_RXN<0>
J 0
(-815 3635);
DISPLAY 0.659574 (-815 3635);
PAINT MONO (-815 3635);
DISPLAY INVISIBLE (-815 3635);
FORCEPROP 1 LASTPIN (-825 3625) BN 0
R 1
J 0
(-832 3573);
DISPLAY 0.617021 (-832 3573);
PAINT GREEN (-832 3573);
FORCEPROP 2 LAST CDS_LIB mstr_standard
J 0
(-825 3575);
PAINT MONO (-825 3575);
DISPLAY INVISIBLE (-825 3575);
FORCEPROP 1 LAST PATH I367
J 0
(-827 3575);
DISPLAY 0.872340 (-827 3575);
PAINT GREEN (-827 3575);
DISPLAY INVISIBLE (-827 3575);
FORCEPROP 1 LAST BODY_TYPE PLUMBING
J 0
(-775 3575);
DISPLAY 2.276596 (-775 3575);
PAINT GREEN (-775 3575);
DISPLAY INVISIBLE (-775 3575);
FORCEPROP 1 LAST HDL_TAP TRUE
J 0
(-505 3445);
DISPLAY 2.276596 (-505 3445);
PAINT GREEN (-505 3445);
DISPLAY INVISIBLE (-505 3445);
FORCEADD OFFPAGE..2
(-675 3525);
FORCEPROP 2 LAST $XR1 30 
J 0
(-366 3525);
DISPLAY 0.638298 (-366 3525);
PAINT MONO (-366 3525);
FORCEPROP 2 LAST $XR0 107 
J 0
(-486 3525);
DISPLAY 0.638298 (-486 3525);
PAINT MONO (-486 3525);
FORCEPROP 2 LAST CDS_LIB mstr_standard
J 0
(-675 3525);
PAINT MONO (-675 3525);
DISPLAY INVISIBLE (-675 3525);
FORCEPROP 2 LAST PATH I368
J 0
(-475 3575);
DISPLAY 1.021277 (-475 3575);
PAINT ORANGE (-475 3575);
DISPLAY INVISIBLE (-475 3575);
FORCEPROP 1 LAST OFFPAGE TRUE
J 0
(-350 3400);
DISPLAY 0.872340 (-350 3400);
PAINT GREEN (-350 3400);
DISPLAY INVISIBLE (-350 3400);
FORCEPROP 1 LAST COMMENT_BODY TRUE
J 0
(-720 3430);
DISPLAY 0.872340 (-720 3430);
PAINT GREEN (-720 3430);
DISPLAY INVISIBLE (-720 3430);
FORCEADD OFFPAGE..2
(-600 2500);
FORCEPROP 2 LAST $XR1 30 
J 0
(-291 2500);
DISPLAY 0.638298 (-291 2500);
PAINT MONO (-291 2500);
FORCEPROP 2 LAST $XR0 107 
J 0
(-411 2500);
DISPLAY 0.638298 (-411 2500);
PAINT MONO (-411 2500);
FORCEPROP 2 LAST CDS_LIB mstr_standard
J 0
(-600 2500);
PAINT MONO (-600 2500);
DISPLAY INVISIBLE (-600 2500);
FORCEPROP 2 LAST PATH I369
J 0
(-400 2550);
DISPLAY 1.021277 (-400 2550);
PAINT ORANGE (-400 2550);
DISPLAY INVISIBLE (-400 2550);
FORCEPROP 1 LAST OFFPAGE TRUE
J 0
(-275 2375);
DISPLAY 0.872340 (-275 2375);
PAINT GREEN (-275 2375);
DISPLAY INVISIBLE (-275 2375);
FORCEPROP 1 LAST COMMENT_BODY TRUE
J 0
(-645 2405);
DISPLAY 0.872340 (-645 2405);
PAINT GREEN (-645 2405);
DISPLAY INVISIBLE (-645 2405);
FORCEADD TAP..7
(-1025 3575);
FORCEPROP 3 LASTPIN (-1025 3625) SIG_NAME P3E_CPU0_PE1_SS_RXN<1>
J 0
(-1015 3635);
DISPLAY 0.659574 (-1015 3635);
PAINT MONO (-1015 3635);
DISPLAY INVISIBLE (-1015 3635);
FORCEPROP 1 LASTPIN (-1025 3625) BN 1
R 1
J 0
(-1032 3573);
DISPLAY 0.617021 (-1032 3573);
PAINT GREEN (-1032 3573);
FORCEPROP 2 LAST CDS_LIB mstr_standard
J 0
(-1025 3575);
PAINT MONO (-1025 3575);
DISPLAY INVISIBLE (-1025 3575);
FORCEPROP 1 LAST PATH I371
J 0
(-1027 3575);
DISPLAY 0.872340 (-1027 3575);
PAINT GREEN (-1027 3575);
DISPLAY INVISIBLE (-1027 3575);
FORCEPROP 1 LAST BODY_TYPE PLUMBING
J 0
(-975 3575);
DISPLAY 2.276596 (-975 3575);
PAINT GREEN (-975 3575);
DISPLAY INVISIBLE (-975 3575);
FORCEPROP 1 LAST HDL_TAP TRUE
J 0
(-705 3445);
DISPLAY 2.276596 (-705 3445);
PAINT GREEN (-705 3445);
DISPLAY INVISIBLE (-705 3445);
FORCEADD TAP..7
(-1225 3575);
FORCEPROP 3 LASTPIN (-1225 3625) SIG_NAME P3E_CPU0_PE1_SS_RXN<2>
J 0
(-1215 3635);
DISPLAY 0.659574 (-1215 3635);
PAINT MONO (-1215 3635);
DISPLAY INVISIBLE (-1215 3635);
FORCEPROP 1 LASTPIN (-1225 3625) BN 2
R 1
J 0
(-1232 3573);
DISPLAY 0.617021 (-1232 3573);
PAINT GREEN (-1232 3573);
FORCEPROP 2 LAST CDS_LIB mstr_standard
J 0
(-1225 3575);
PAINT MONO (-1225 3575);
DISPLAY INVISIBLE (-1225 3575);
FORCEPROP 1 LAST PATH I372
J 0
(-1227 3575);
DISPLAY 0.872340 (-1227 3575);
PAINT GREEN (-1227 3575);
DISPLAY INVISIBLE (-1227 3575);
FORCEPROP 1 LAST BODY_TYPE PLUMBING
J 0
(-1175 3575);
DISPLAY 2.276596 (-1175 3575);
PAINT GREEN (-1175 3575);
DISPLAY INVISIBLE (-1175 3575);
FORCEPROP 1 LAST HDL_TAP TRUE
J 0
(-905 3445);
DISPLAY 2.276596 (-905 3445);
PAINT GREEN (-905 3445);
DISPLAY INVISIBLE (-905 3445);
FORCEADD TAP..3
(-800 3350);
FORCEPROP 3 LASTPIN (-800 3300) SIG_NAME P3E_CPU0_PE1_SS_R_RXP<0>
J 0
(-790 3310);
DISPLAY 0.659574 (-790 3310);
PAINT MONO (-790 3310);
DISPLAY INVISIBLE (-790 3310);
FORCEPROP 1 LASTPIN (-800 3300) BN 0
R 1
J 0
(-807 3288);
DISPLAY 0.617021 (-807 3288);
PAINT GREEN (-807 3288);
FORCEPROP 1 LAST PATH I373
J 0
(-802 3350);
DISPLAY 0.872340 (-802 3350);
PAINT GREEN (-802 3350);
DISPLAY INVISIBLE (-802 3350);
FORCEPROP 2 LAST CDS_LIB mstr_standard
J 0
(-800 3350);
PAINT MONO (-800 3350);
DISPLAY INVISIBLE (-800 3350);
FORCEPROP 1 LAST BODY_TYPE PLUMBING
J 0
(-750 3300);
DISPLAY 2.276596 (-750 3300);
PAINT GREEN (-750 3300);
DISPLAY INVISIBLE (-750 3300);
FORCEPROP 1 LAST HDL_TAP TRUE
J 0
(-480 3220);
DISPLAY 2.276596 (-480 3220);
PAINT GREEN (-480 3220);
DISPLAY INVISIBLE (-480 3220);
FORCEADD TAP..3
(-1000 3350);
FORCEPROP 3 LASTPIN (-1000 3300) SIG_NAME P3E_CPU0_PE1_SS_R_RXP<1>
J 0
(-990 3310);
DISPLAY 0.659574 (-990 3310);
PAINT MONO (-990 3310);
DISPLAY INVISIBLE (-990 3310);
FORCEPROP 1 LASTPIN (-1000 3300) BN 1
R 1
J 0
(-1007 3288);
DISPLAY 0.617021 (-1007 3288);
PAINT GREEN (-1007 3288);
FORCEPROP 1 LAST PATH I375
J 0
(-1002 3350);
DISPLAY 0.872340 (-1002 3350);
PAINT GREEN (-1002 3350);
DISPLAY INVISIBLE (-1002 3350);
FORCEPROP 2 LAST CDS_LIB mstr_standard
J 0
(-1000 3350);
PAINT MONO (-1000 3350);
DISPLAY INVISIBLE (-1000 3350);
FORCEPROP 1 LAST BODY_TYPE PLUMBING
J 0
(-950 3300);
DISPLAY 2.276596 (-950 3300);
PAINT GREEN (-950 3300);
DISPLAY INVISIBLE (-950 3300);
FORCEPROP 1 LAST HDL_TAP TRUE
J 0
(-680 3220);
DISPLAY 2.276596 (-680 3220);
PAINT GREEN (-680 3220);
DISPLAY INVISIBLE (-680 3220);
FORCEADD TAP..3
(-1200 3350);
FORCEPROP 3 LASTPIN (-1200 3300) SIG_NAME P3E_CPU0_PE1_SS_R_RXP<2>
J 0
(-1190 3310);
DISPLAY 0.659574 (-1190 3310);
PAINT MONO (-1190 3310);
DISPLAY INVISIBLE (-1190 3310);
FORCEPROP 1 LASTPIN (-1200 3300) BN 2
R 1
J 0
(-1207 3288);
DISPLAY 0.617021 (-1207 3288);
PAINT GREEN (-1207 3288);
FORCEPROP 1 LAST PATH I376
J 0
(-1202 3350);
DISPLAY 0.872340 (-1202 3350);
PAINT GREEN (-1202 3350);
DISPLAY INVISIBLE (-1202 3350);
FORCEPROP 2 LAST CDS_LIB mstr_standard
J 0
(-1200 3350);
PAINT MONO (-1200 3350);
DISPLAY INVISIBLE (-1200 3350);
FORCEPROP 1 LAST BODY_TYPE PLUMBING
J 0
(-1150 3300);
DISPLAY 2.276596 (-1150 3300);
PAINT GREEN (-1150 3300);
DISPLAY INVISIBLE (-1150 3300);
FORCEPROP 1 LAST HDL_TAP TRUE
J 0
(-880 3220);
DISPLAY 1.829787 (-880 3220);
PAINT GREEN (-880 3220);
DISPLAY INVISIBLE (-880 3220);
FORCEADD TAP..7
(-1425 3575);
FORCEPROP 3 LASTPIN (-1425 3625) SIG_NAME P3E_CPU0_PE1_SS_RXN<3>
J 0
(-1415 3635);
DISPLAY 0.659574 (-1415 3635);
PAINT MONO (-1415 3635);
DISPLAY INVISIBLE (-1415 3635);
FORCEPROP 1 LASTPIN (-1425 3625) BN 3
R 1
J 0
(-1432 3573);
DISPLAY 0.617021 (-1432 3573);
PAINT GREEN (-1432 3573);
FORCEPROP 2 LAST CDS_LIB mstr_standard
J 0
(-1425 3575);
PAINT MONO (-1425 3575);
DISPLAY INVISIBLE (-1425 3575);
FORCEPROP 1 LAST PATH I379
J 0
(-1427 3575);
DISPLAY 0.872340 (-1427 3575);
PAINT GREEN (-1427 3575);
DISPLAY INVISIBLE (-1427 3575);
FORCEPROP 1 LAST BODY_TYPE PLUMBING
J 0
(-1375 3575);
DISPLAY 2.276596 (-1375 3575);
PAINT GREEN (-1375 3575);
DISPLAY INVISIBLE (-1375 3575);
FORCEPROP 1 LAST HDL_TAP TRUE
J 0
(-1105 3445);
DISPLAY 2.276596 (-1105 3445);
PAINT GREEN (-1105 3445);
DISPLAY INVISIBLE (-1105 3445);
FORCEADD TAP..7
(-1625 3575);
FORCEPROP 3 LASTPIN (-1625 3625) SIG_NAME P3E_CPU0_PE1_SS_RXN<4>
J 0
(-1615 3635);
DISPLAY 0.659574 (-1615 3635);
PAINT MONO (-1615 3635);
DISPLAY INVISIBLE (-1615 3635);
FORCEPROP 1 LASTPIN (-1625 3625) BN 4
R 1
J 0
(-1632 3573);
DISPLAY 0.617021 (-1632 3573);
PAINT GREEN (-1632 3573);
FORCEPROP 2 LAST CDS_LIB mstr_standard
J 0
(-1625 3575);
PAINT MONO (-1625 3575);
DISPLAY INVISIBLE (-1625 3575);
FORCEPROP 1 LAST PATH I380
J 0
(-1627 3575);
DISPLAY 0.872340 (-1627 3575);
PAINT GREEN (-1627 3575);
DISPLAY INVISIBLE (-1627 3575);
FORCEPROP 1 LAST BODY_TYPE PLUMBING
J 0
(-1575 3575);
DISPLAY 2.276596 (-1575 3575);
PAINT GREEN (-1575 3575);
DISPLAY INVISIBLE (-1575 3575);
FORCEPROP 1 LAST HDL_TAP TRUE
J 0
(-1305 3445);
DISPLAY 2.276596 (-1305 3445);
PAINT GREEN (-1305 3445);
DISPLAY INVISIBLE (-1305 3445);
FORCEADD TAP..7
(-1825 3575);
FORCEPROP 3 LASTPIN (-1825 3625) SIG_NAME P3E_CPU0_PE1_SS_RXN<5>
J 0
(-1815 3635);
DISPLAY 0.659574 (-1815 3635);
PAINT MONO (-1815 3635);
DISPLAY INVISIBLE (-1815 3635);
FORCEPROP 1 LASTPIN (-1825 3625) BN 5
R 1
J 0
(-1832 3573);
DISPLAY 0.617021 (-1832 3573);
PAINT GREEN (-1832 3573);
FORCEPROP 2 LAST CDS_LIB mstr_standard
J 0
(-1825 3575);
PAINT MONO (-1825 3575);
DISPLAY INVISIBLE (-1825 3575);
FORCEPROP 1 LAST PATH I382
J 0
(-1827 3575);
DISPLAY 0.872340 (-1827 3575);
PAINT GREEN (-1827 3575);
DISPLAY INVISIBLE (-1827 3575);
FORCEPROP 1 LAST BODY_TYPE PLUMBING
J 0
(-1775 3575);
DISPLAY 2.276596 (-1775 3575);
PAINT GREEN (-1775 3575);
DISPLAY INVISIBLE (-1775 3575);
FORCEPROP 1 LAST HDL_TAP TRUE
J 0
(-1505 3445);
DISPLAY 2.276596 (-1505 3445);
PAINT GREEN (-1505 3445);
DISPLAY INVISIBLE (-1505 3445);
FORCEADD TAP..3
(-1400 3350);
FORCEPROP 3 LASTPIN (-1400 3300) SIG_NAME P3E_CPU0_PE1_SS_R_RXP<3>
J 0
(-1390 3310);
DISPLAY 0.659574 (-1390 3310);
PAINT MONO (-1390 3310);
DISPLAY INVISIBLE (-1390 3310);
FORCEPROP 1 LASTPIN (-1400 3300) BN 3
R 1
J 0
(-1407 3288);
DISPLAY 0.617021 (-1407 3288);
PAINT GREEN (-1407 3288);
FORCEPROP 2 LAST CDS_LIB mstr_standard
J 0
(-1400 3350);
PAINT MONO (-1400 3350);
DISPLAY INVISIBLE (-1400 3350);
FORCEPROP 1 LAST PATH I383
J 0
(-1402 3350);
DISPLAY 0.872340 (-1402 3350);
PAINT GREEN (-1402 3350);
DISPLAY INVISIBLE (-1402 3350);
FORCEPROP 1 LAST BODY_TYPE PLUMBING
J 0
(-1350 3300);
DISPLAY 2.276596 (-1350 3300);
PAINT GREEN (-1350 3300);
DISPLAY INVISIBLE (-1350 3300);
FORCEPROP 1 LAST HDL_TAP TRUE
J 0
(-1080 3220);
DISPLAY 2.276596 (-1080 3220);
PAINT GREEN (-1080 3220);
DISPLAY INVISIBLE (-1080 3220);
FORCEADD TAP..3
(-1600 3350);
FORCEPROP 3 LASTPIN (-1600 3300) SIG_NAME P3E_CPU0_PE1_SS_R_RXP<4>
J 0
(-1590 3310);
DISPLAY 0.659574 (-1590 3310);
PAINT MONO (-1590 3310);
DISPLAY INVISIBLE (-1590 3310);
FORCEPROP 1 LASTPIN (-1600 3300) BN 4
R 1
J 0
(-1607 3288);
DISPLAY 0.617021 (-1607 3288);
PAINT GREEN (-1607 3288);
FORCEPROP 2 LAST CDS_LIB mstr_standard
J 0
(-1600 3350);
PAINT MONO (-1600 3350);
DISPLAY INVISIBLE (-1600 3350);
FORCEPROP 1 LAST PATH I384
J 0
(-1602 3350);
DISPLAY 0.872340 (-1602 3350);
PAINT GREEN (-1602 3350);
DISPLAY INVISIBLE (-1602 3350);
FORCEPROP 1 LAST BODY_TYPE PLUMBING
J 0
(-1550 3300);
DISPLAY 2.276596 (-1550 3300);
PAINT GREEN (-1550 3300);
DISPLAY INVISIBLE (-1550 3300);
FORCEPROP 1 LAST HDL_TAP TRUE
J 0
(-1280 3220);
DISPLAY 2.276596 (-1280 3220);
PAINT GREEN (-1280 3220);
DISPLAY INVISIBLE (-1280 3220);
FORCEADD TAP..7
(-800 2550);
FORCEPROP 3 LASTPIN (-800 2600) SIG_NAME P3E_CPU0_PE1_SS_RXP<0>
J 0
(-790 2610);
DISPLAY 0.659574 (-790 2610);
PAINT MONO (-790 2610);
DISPLAY INVISIBLE (-790 2610);
FORCEPROP 1 LASTPIN (-800 2600) BN 0
R 1
J 0
(-807 2548);
DISPLAY 0.617021 (-807 2548);
PAINT GREEN (-807 2548);
FORCEPROP 2 LAST CDS_LIB mstr_standard
J 0
(-800 2550);
PAINT MONO (-800 2550);
DISPLAY INVISIBLE (-800 2550);
FORCEPROP 1 LAST PATH I386
J 0
(-802 2550);
DISPLAY 0.872340 (-802 2550);
PAINT GREEN (-802 2550);
DISPLAY INVISIBLE (-802 2550);
FORCEPROP 1 LAST BODY_TYPE PLUMBING
J 0
(-750 2550);
DISPLAY 2.276596 (-750 2550);
PAINT GREEN (-750 2550);
DISPLAY INVISIBLE (-750 2550);
FORCEPROP 1 LAST HDL_TAP TRUE
J 0
(-480 2420);
DISPLAY 2.276596 (-480 2420);
PAINT GREEN (-480 2420);
DISPLAY INVISIBLE (-480 2420);
FORCEADD TAP..7
(-1000 2550);
FORCEPROP 3 LASTPIN (-1000 2600) SIG_NAME P3E_CPU0_PE1_SS_RXP<1>
J 0
(-990 2610);
DISPLAY 0.659574 (-990 2610);
PAINT MONO (-990 2610);
DISPLAY INVISIBLE (-990 2610);
FORCEPROP 1 LASTPIN (-1000 2600) BN 1
R 1
J 0
(-1007 2548);
DISPLAY 0.617021 (-1007 2548);
PAINT GREEN (-1007 2548);
FORCEPROP 2 LAST CDS_LIB mstr_standard
J 0
(-1000 2550);
PAINT MONO (-1000 2550);
DISPLAY INVISIBLE (-1000 2550);
FORCEPROP 1 LAST PATH I388
J 0
(-1002 2550);
DISPLAY 0.872340 (-1002 2550);
PAINT GREEN (-1002 2550);
DISPLAY INVISIBLE (-1002 2550);
FORCEPROP 1 LAST BODY_TYPE PLUMBING
J 0
(-950 2550);
DISPLAY 2.276596 (-950 2550);
PAINT GREEN (-950 2550);
DISPLAY INVISIBLE (-950 2550);
FORCEPROP 1 LAST HDL_TAP TRUE
J 0
(-680 2420);
DISPLAY 2.276596 (-680 2420);
PAINT GREEN (-680 2420);
DISPLAY INVISIBLE (-680 2420);
FORCEADD TAP..7
(-1200 2550);
FORCEPROP 3 LASTPIN (-1200 2600) SIG_NAME P3E_CPU0_PE1_SS_RXP<2>
J 0
(-1190 2610);
DISPLAY 0.659574 (-1190 2610);
PAINT MONO (-1190 2610);
DISPLAY INVISIBLE (-1190 2610);
FORCEPROP 1 LASTPIN (-1200 2600) BN 2
R 1
J 0
(-1207 2548);
DISPLAY 0.617021 (-1207 2548);
PAINT GREEN (-1207 2548);
FORCEPROP 2 LAST CDS_LIB mstr_standard
J 0
(-1200 2550);
PAINT MONO (-1200 2550);
DISPLAY INVISIBLE (-1200 2550);
FORCEPROP 1 LAST PATH I389
J 0
(-1202 2550);
DISPLAY 0.872340 (-1202 2550);
PAINT GREEN (-1202 2550);
DISPLAY INVISIBLE (-1202 2550);
FORCEPROP 1 LAST BODY_TYPE PLUMBING
J 0
(-1150 2550);
DISPLAY 2.276596 (-1150 2550);
PAINT GREEN (-1150 2550);
DISPLAY INVISIBLE (-1150 2550);
FORCEPROP 1 LAST HDL_TAP TRUE
J 0
(-880 2420);
DISPLAY 2.276596 (-880 2420);
PAINT GREEN (-880 2420);
DISPLAY INVISIBLE (-880 2420);
FORCEADD TAP..7
(-1400 2550);
FORCEPROP 3 LASTPIN (-1400 2600) SIG_NAME P3E_CPU0_PE1_SS_RXP<3>
J 0
(-1390 2610);
DISPLAY 0.659574 (-1390 2610);
PAINT MONO (-1390 2610);
DISPLAY INVISIBLE (-1390 2610);
FORCEPROP 1 LASTPIN (-1400 2600) BN 3
R 1
J 0
(-1407 2548);
DISPLAY 0.617021 (-1407 2548);
PAINT GREEN (-1407 2548);
FORCEPROP 2 LAST CDS_LIB mstr_standard
J 0
(-1400 2550);
PAINT MONO (-1400 2550);
DISPLAY INVISIBLE (-1400 2550);
FORCEPROP 1 LAST PATH I391
J 0
(-1402 2550);
DISPLAY 0.872340 (-1402 2550);
PAINT GREEN (-1402 2550);
DISPLAY INVISIBLE (-1402 2550);
FORCEPROP 1 LAST BODY_TYPE PLUMBING
J 0
(-1350 2550);
DISPLAY 2.276596 (-1350 2550);
PAINT GREEN (-1350 2550);
DISPLAY INVISIBLE (-1350 2550);
FORCEPROP 1 LAST HDL_TAP TRUE
J 0
(-1080 2420);
DISPLAY 2.276596 (-1080 2420);
PAINT GREEN (-1080 2420);
DISPLAY INVISIBLE (-1080 2420);
FORCEADD TAP..7
(-1600 2550);
FORCEPROP 3 LASTPIN (-1600 2600) SIG_NAME P3E_CPU0_PE1_SS_RXP<4>
J 0
(-1590 2610);
DISPLAY 0.659574 (-1590 2610);
PAINT MONO (-1590 2610);
DISPLAY INVISIBLE (-1590 2610);
FORCEPROP 1 LASTPIN (-1600 2600) BN 4
R 1
J 0
(-1607 2548);
DISPLAY 0.617021 (-1607 2548);
PAINT GREEN (-1607 2548);
FORCEPROP 2 LAST CDS_LIB mstr_standard
J 0
(-1600 2550);
PAINT MONO (-1600 2550);
DISPLAY INVISIBLE (-1600 2550);
FORCEPROP 1 LAST PATH I392
J 0
(-1602 2550);
DISPLAY 0.872340 (-1602 2550);
PAINT GREEN (-1602 2550);
DISPLAY INVISIBLE (-1602 2550);
FORCEPROP 1 LAST BODY_TYPE PLUMBING
J 0
(-1550 2550);
DISPLAY 2.276596 (-1550 2550);
PAINT GREEN (-1550 2550);
DISPLAY INVISIBLE (-1550 2550);
FORCEPROP 1 LAST HDL_TAP TRUE
J 0
(-1280 2420);
DISPLAY 2.276596 (-1280 2420);
PAINT GREEN (-1280 2420);
DISPLAY INVISIBLE (-1280 2420);
FORCEADD TAP..7
(-2025 3575);
FORCEPROP 3 LASTPIN (-2025 3625) SIG_NAME P3E_CPU0_PE1_SS_RXN<6>
J 0
(-2015 3635);
DISPLAY 0.659574 (-2015 3635);
PAINT MONO (-2015 3635);
DISPLAY INVISIBLE (-2015 3635);
FORCEPROP 1 LASTPIN (-2025 3625) BN 6
R 1
J 0
(-2032 3573);
DISPLAY 0.617021 (-2032 3573);
PAINT GREEN (-2032 3573);
FORCEPROP 2 LAST CDS_LIB mstr_standard
J 0
(-2025 3575);
PAINT MONO (-2025 3575);
DISPLAY INVISIBLE (-2025 3575);
FORCEPROP 1 LAST PATH I393
J 0
(-2027 3575);
DISPLAY 0.872340 (-2027 3575);
PAINT GREEN (-2027 3575);
DISPLAY INVISIBLE (-2027 3575);
FORCEPROP 1 LAST BODY_TYPE PLUMBING
J 0
(-1975 3575);
DISPLAY 2.276596 (-1975 3575);
PAINT GREEN (-1975 3575);
DISPLAY INVISIBLE (-1975 3575);
FORCEPROP 1 LAST HDL_TAP TRUE
J 0
(-1705 3445);
DISPLAY 2.276596 (-1705 3445);
PAINT GREEN (-1705 3445);
DISPLAY INVISIBLE (-1705 3445);
FORCEADD TAP..7
(-2225 3575);
FORCEPROP 3 LASTPIN (-2225 3625) SIG_NAME P3E_CPU0_PE1_SS_RXN<7>
J 0
(-2215 3635);
DISPLAY 0.659574 (-2215 3635);
PAINT MONO (-2215 3635);
DISPLAY INVISIBLE (-2215 3635);
FORCEPROP 1 LASTPIN (-2225 3625) BN 7
R 1
J 0
(-2232 3573);
DISPLAY 0.617021 (-2232 3573);
PAINT GREEN (-2232 3573);
FORCEPROP 2 LAST CDS_LIB mstr_standard
J 0
(-2225 3575);
PAINT MONO (-2225 3575);
DISPLAY INVISIBLE (-2225 3575);
FORCEPROP 1 LAST PATH I395
J 0
(-2227 3575);
DISPLAY 0.872340 (-2227 3575);
PAINT GREEN (-2227 3575);
DISPLAY INVISIBLE (-2227 3575);
FORCEPROP 1 LAST BODY_TYPE PLUMBING
J 0
(-2175 3575);
DISPLAY 2.276596 (-2175 3575);
PAINT GREEN (-2175 3575);
DISPLAY INVISIBLE (-2175 3575);
FORCEPROP 1 LAST HDL_TAP TRUE
J 0
(-1905 3445);
DISPLAY 2.276596 (-1905 3445);
PAINT GREEN (-1905 3445);
DISPLAY INVISIBLE (-1905 3445);
FORCEADD TAP..3
(-1800 3350);
FORCEPROP 3 LASTPIN (-1800 3300) SIG_NAME P3E_CPU0_PE1_SS_R_RXP<5>
J 0
(-1790 3310);
DISPLAY 0.659574 (-1790 3310);
PAINT MONO (-1790 3310);
DISPLAY INVISIBLE (-1790 3310);
FORCEPROP 1 LASTPIN (-1800 3300) BN 5
R 1
J 0
(-1807 3288);
DISPLAY 0.617021 (-1807 3288);
PAINT GREEN (-1807 3288);
FORCEPROP 2 LAST CDS_LIB mstr_standard
J 0
(-1800 3350);
PAINT MONO (-1800 3350);
DISPLAY INVISIBLE (-1800 3350);
FORCEPROP 1 LAST PATH I396
J 0
(-1802 3350);
DISPLAY 0.872340 (-1802 3350);
PAINT GREEN (-1802 3350);
DISPLAY INVISIBLE (-1802 3350);
FORCEPROP 1 LAST BODY_TYPE PLUMBING
J 0
(-1750 3300);
DISPLAY 2.276596 (-1750 3300);
PAINT GREEN (-1750 3300);
DISPLAY INVISIBLE (-1750 3300);
FORCEPROP 1 LAST HDL_TAP TRUE
J 0
(-1480 3220);
DISPLAY 2.276596 (-1480 3220);
PAINT GREEN (-1480 3220);
DISPLAY INVISIBLE (-1480 3220);
FORCEADD TAP..3
(-2000 3350);
FORCEPROP 3 LASTPIN (-2000 3300) SIG_NAME P3E_CPU0_PE1_SS_R_RXP<6>
J 0
(-1990 3310);
DISPLAY 0.659574 (-1990 3310);
PAINT MONO (-1990 3310);
DISPLAY INVISIBLE (-1990 3310);
FORCEPROP 1 LASTPIN (-2000 3300) BN 6
R 1
J 0
(-2007 3288);
DISPLAY 0.617021 (-2007 3288);
PAINT GREEN (-2007 3288);
FORCEPROP 1 LAST PATH I397
J 0
(-2002 3350);
DISPLAY 0.872340 (-2002 3350);
PAINT GREEN (-2002 3350);
DISPLAY INVISIBLE (-2002 3350);
FORCEPROP 2 LAST CDS_LIB mstr_standard
J 0
(-2000 3350);
PAINT MONO (-2000 3350);
DISPLAY INVISIBLE (-2000 3350);
FORCEPROP 1 LAST BODY_TYPE PLUMBING
J 0
(-1950 3300);
DISPLAY 2.276596 (-1950 3300);
PAINT GREEN (-1950 3300);
DISPLAY INVISIBLE (-1950 3300);
FORCEPROP 1 LAST HDL_TAP TRUE
J 0
(-1680 3220);
DISPLAY 2.276596 (-1680 3220);
PAINT GREEN (-1680 3220);
DISPLAY INVISIBLE (-1680 3220);
FORCEADD TAP..3
(-2200 3350);
FORCEPROP 3 LASTPIN (-2200 3300) SIG_NAME P3E_CPU0_PE1_SS_R_RXP<7>
J 0
(-2190 3310);
DISPLAY 0.659574 (-2190 3310);
PAINT MONO (-2190 3310);
DISPLAY INVISIBLE (-2190 3310);
FORCEPROP 1 LASTPIN (-2200 3300) BN 7
R 1
J 0
(-2207 3288);
DISPLAY 0.617021 (-2207 3288);
PAINT GREEN (-2207 3288);
FORCEPROP 2 LAST CDS_LIB mstr_standard
J 0
(-2200 3350);
PAINT MONO (-2200 3350);
DISPLAY INVISIBLE (-2200 3350);
FORCEPROP 1 LAST PATH I399
J 0
(-2202 3350);
DISPLAY 0.872340 (-2202 3350);
PAINT GREEN (-2202 3350);
DISPLAY INVISIBLE (-2202 3350);
FORCEPROP 1 LAST BODY_TYPE PLUMBING
J 0
(-2150 3300);
DISPLAY 2.276596 (-2150 3300);
PAINT GREEN (-2150 3300);
DISPLAY INVISIBLE (-2150 3300);
FORCEPROP 1 LAST HDL_TAP TRUE
J 0
(-1880 3220);
DISPLAY 2.276596 (-1880 3220);
PAINT GREEN (-1880 3220);
DISPLAY INVISIBLE (-1880 3220);
FORCEADD OFFPAGE..1
(-2375 3400);
FORCEPROP 2 LAST $XR0 109 
J 0
(-2627 3400);
DISPLAY 0.638298 (-2627 3400);
PAINT MONO (-2627 3400);
FORCEPROP 2 LAST PATH I400
J 0
(-2575 3450);
DISPLAY 1.021277 (-2575 3450);
PAINT ORANGE (-2575 3450);
DISPLAY INVISIBLE (-2575 3450);
FORCEPROP 2 LAST CDS_LIB mstr_standard
J 0
(-2375 3400);
PAINT MONO (-2375 3400);
DISPLAY INVISIBLE (-2375 3400);
FORCEPROP 1 LAST OFFPAGE TRUE
J 0
(-2055 3270);
PAINT GREEN (-2055 3270);
DISPLAY INVISIBLE (-2055 3270);
FORCEPROP 1 LAST COMMENT_BODY TRUE
J 0
(-2255 3300);
DISPLAY 2.276596 (-2255 3300);
PAINT GREEN (-2255 3300);
DISPLAY INVISIBLE (-2255 3300);
FORCEADD TAP..7
(-1800 2550);
FORCEPROP 3 LASTPIN (-1800 2600) SIG_NAME P3E_CPU0_PE1_SS_RXP<5>
J 0
(-1790 2610);
DISPLAY 0.659574 (-1790 2610);
PAINT MONO (-1790 2610);
DISPLAY INVISIBLE (-1790 2610);
FORCEPROP 1 LASTPIN (-1800 2600) BN 5
R 1
J 0
(-1807 2548);
DISPLAY 0.617021 (-1807 2548);
PAINT GREEN (-1807 2548);
FORCEPROP 2 LAST CDS_LIB mstr_standard
J 0
(-1800 2550);
PAINT MONO (-1800 2550);
DISPLAY INVISIBLE (-1800 2550);
FORCEPROP 1 LAST PATH I402
J 0
(-1802 2550);
DISPLAY 0.872340 (-1802 2550);
PAINT GREEN (-1802 2550);
DISPLAY INVISIBLE (-1802 2550);
FORCEPROP 1 LAST BODY_TYPE PLUMBING
J 0
(-1750 2550);
DISPLAY 2.276596 (-1750 2550);
PAINT GREEN (-1750 2550);
DISPLAY INVISIBLE (-1750 2550);
FORCEPROP 1 LAST HDL_TAP TRUE
J 0
(-1480 2420);
DISPLAY 2.276596 (-1480 2420);
PAINT GREEN (-1480 2420);
DISPLAY INVISIBLE (-1480 2420);
FORCEADD TAP..7
(-2000 2550);
FORCEPROP 3 LASTPIN (-2000 2600) SIG_NAME P3E_CPU0_PE1_SS_RXP<6>
J 0
(-1990 2610);
DISPLAY 0.659574 (-1990 2610);
PAINT MONO (-1990 2610);
DISPLAY INVISIBLE (-1990 2610);
FORCEPROP 1 LASTPIN (-2000 2600) BN 6
R 1
J 0
(-2007 2548);
DISPLAY 0.617021 (-2007 2548);
PAINT GREEN (-2007 2548);
FORCEPROP 2 LAST CDS_LIB mstr_standard
J 0
(-2000 2550);
PAINT MONO (-2000 2550);
DISPLAY INVISIBLE (-2000 2550);
FORCEPROP 1 LAST PATH I403
J 0
(-2002 2550);
DISPLAY 0.872340 (-2002 2550);
PAINT GREEN (-2002 2550);
DISPLAY INVISIBLE (-2002 2550);
FORCEPROP 1 LAST BODY_TYPE PLUMBING
J 0
(-1950 2550);
DISPLAY 2.276596 (-1950 2550);
PAINT GREEN (-1950 2550);
DISPLAY INVISIBLE (-1950 2550);
FORCEPROP 1 LAST HDL_TAP TRUE
J 0
(-1680 2420);
DISPLAY 2.276596 (-1680 2420);
PAINT GREEN (-1680 2420);
DISPLAY INVISIBLE (-1680 2420);
FORCEADD TAP..7
(-2200 2550);
FORCEPROP 3 LASTPIN (-2200 2600) SIG_NAME P3E_CPU0_PE1_SS_RXP<7>
J 0
(-2190 2610);
DISPLAY 0.659574 (-2190 2610);
PAINT MONO (-2190 2610);
DISPLAY INVISIBLE (-2190 2610);
FORCEPROP 1 LASTPIN (-2200 2600) BN 7
R 1
J 0
(-2207 2548);
DISPLAY 0.617021 (-2207 2548);
PAINT GREEN (-2207 2548);
FORCEPROP 1 LAST PATH I405
J 0
(-2202 2550);
DISPLAY 0.872340 (-2202 2550);
PAINT GREEN (-2202 2550);
DISPLAY INVISIBLE (-2202 2550);
FORCEPROP 2 LAST CDS_LIB mstr_standard
J 0
(-2200 2550);
PAINT MONO (-2200 2550);
DISPLAY INVISIBLE (-2200 2550);
FORCEPROP 1 LAST BODY_TYPE PLUMBING
J 0
(-2150 2550);
DISPLAY 2.276596 (-2150 2550);
PAINT GREEN (-2150 2550);
DISPLAY INVISIBLE (-2150 2550);
FORCEPROP 1 LAST HDL_TAP TRUE
J 0
(-1880 2420);
DISPLAY 2.276596 (-1880 2420);
PAINT GREEN (-1880 2420);
DISPLAY INVISIBLE (-1880 2420);
FORCEADD TAP..7
(-5450 2425);
FORCEPROP 3 LASTPIN (-5450 2475) SIG_NAME P3E_CPU0_PE1_SS_C_TXP<6>
J 0
(-5440 2485);
DISPLAY 0.659574 (-5440 2485);
PAINT MONO (-5440 2485);
DISPLAY INVISIBLE (-5440 2485);
FORCEPROP 1 LASTPIN (-5450 2475) BN 6
R 1
J 0
(-5457 2423);
DISPLAY 0.617021 (-5457 2423);
PAINT GREEN (-5457 2423);
FORCEPROP 1 LAST PATH I406
J 0
(-5452 2425);
DISPLAY 0.872340 (-5452 2425);
PAINT GREEN (-5452 2425);
DISPLAY INVISIBLE (-5452 2425);
FORCEPROP 2 LAST CDS_LIB mstr_standard
J 0
(-5450 2425);
PAINT ORANGE (-5450 2425);
DISPLAY INVISIBLE (-5450 2425);
FORCEPROP 1 LAST BODY_TYPE PLUMBING
J 0
(-5400 2425);
DISPLAY 2.276596 (-5400 2425);
PAINT GREEN (-5400 2425);
DISPLAY INVISIBLE (-5400 2425);
FORCEPROP 1 LAST HDL_TAP TRUE
J 0
(-5130 2295);
DISPLAY 2.276596 (-5130 2295);
PAINT GREEN (-5130 2295);
DISPLAY INVISIBLE (-5130 2295);
FORCEADD TAP..3
(-4300 4225);
FORCEPROP 3 LASTPIN (-4300 4175) SIG_NAME P3E_CPU0_PE1_SS_TXN<0>
J 0
(-4290 4185);
DISPLAY 0.659574 (-4290 4185);
PAINT MONO (-4290 4185);
DISPLAY INVISIBLE (-4290 4185);
FORCEPROP 1 LASTPIN (-4300 4175) BN 0
R 1
J 0
(-4307 4163);
DISPLAY 0.617021 (-4307 4163);
PAINT GREEN (-4307 4163);
FORCEPROP 2 LAST CDS_LIB mstr_standard
J 0
(-4300 4225);
PAINT ORANGE (-4300 4225);
DISPLAY INVISIBLE (-4300 4225);
FORCEPROP 1 LAST PATH I407
J 0
(-4302 4225);
DISPLAY 0.872340 (-4302 4225);
PAINT GREEN (-4302 4225);
DISPLAY INVISIBLE (-4302 4225);
FORCEPROP 1 LAST BODY_TYPE PLUMBING
J 0
(-4250 4175);
DISPLAY 2.276596 (-4250 4175);
PAINT GREEN (-4250 4175);
DISPLAY INVISIBLE (-4250 4175);
FORCEPROP 1 LAST HDL_TAP TRUE
J 0
(-3980 4095);
DISPLAY 2.276596 (-3980 4095);
PAINT GREEN (-3980 4095);
DISPLAY INVISIBLE (-3980 4095);
FORCEADD TAP..3
(-4500 4225);
FORCEPROP 3 LASTPIN (-4500 4175) SIG_NAME P3E_CPU0_PE1_SS_TXN<1>
J 0
(-4490 4185);
DISPLAY 0.659574 (-4490 4185);
PAINT MONO (-4490 4185);
DISPLAY INVISIBLE (-4490 4185);
FORCEPROP 1 LASTPIN (-4500 4175) BN 1
R 1
J 0
(-4507 4163);
DISPLAY 0.617021 (-4507 4163);
PAINT GREEN (-4507 4163);
FORCEPROP 2 LAST CDS_LIB mstr_standard
J 0
(-4500 4225);
PAINT ORANGE (-4500 4225);
DISPLAY INVISIBLE (-4500 4225);
FORCEPROP 1 LAST PATH I408
J 0
(-4502 4225);
DISPLAY 0.872340 (-4502 4225);
PAINT GREEN (-4502 4225);
DISPLAY INVISIBLE (-4502 4225);
FORCEPROP 1 LAST BODY_TYPE PLUMBING
J 0
(-4450 4175);
DISPLAY 2.276596 (-4450 4175);
PAINT GREEN (-4450 4175);
DISPLAY INVISIBLE (-4450 4175);
FORCEPROP 1 LAST HDL_TAP TRUE
J 0
(-4180 4095);
DISPLAY 2.276596 (-4180 4095);
PAINT GREEN (-4180 4095);
DISPLAY INVISIBLE (-4180 4095);
FORCEADD TAP..3
(-4700 4225);
FORCEPROP 3 LASTPIN (-4700 4175) SIG_NAME P3E_CPU0_PE1_SS_TXN<2>
J 0
(-4690 4185);
DISPLAY 0.659574 (-4690 4185);
PAINT MONO (-4690 4185);
DISPLAY INVISIBLE (-4690 4185);
FORCEPROP 1 LASTPIN (-4700 4175) BN 2
R 1
J 0
(-4707 4163);
DISPLAY 0.617021 (-4707 4163);
PAINT GREEN (-4707 4163);
FORCEPROP 2 LAST CDS_LIB mstr_standard
J 0
(-4700 4225);
PAINT ORANGE (-4700 4225);
DISPLAY INVISIBLE (-4700 4225);
FORCEPROP 1 LAST PATH I409
J 0
(-4702 4225);
DISPLAY 0.872340 (-4702 4225);
PAINT GREEN (-4702 4225);
DISPLAY INVISIBLE (-4702 4225);
FORCEPROP 1 LAST BODY_TYPE PLUMBING
J 0
(-4650 4175);
DISPLAY 2.276596 (-4650 4175);
PAINT GREEN (-4650 4175);
DISPLAY INVISIBLE (-4650 4175);
FORCEPROP 1 LAST HDL_TAP TRUE
J 0
(-4380 4095);
DISPLAY 2.276596 (-4380 4095);
PAINT GREEN (-4380 4095);
DISPLAY INVISIBLE (-4380 4095);
FORCEADD TAP..3
(-4900 4225);
FORCEPROP 3 LASTPIN (-4900 4175) SIG_NAME P3E_CPU0_PE1_SS_TXN<3>
J 0
(-4890 4185);
DISPLAY 0.659574 (-4890 4185);
PAINT MONO (-4890 4185);
DISPLAY INVISIBLE (-4890 4185);
FORCEPROP 1 LASTPIN (-4900 4175) BN 3
R 1
J 0
(-4907 4163);
DISPLAY 0.617021 (-4907 4163);
PAINT GREEN (-4907 4163);
FORCEPROP 2 LAST CDS_LIB mstr_standard
J 0
(-4900 4225);
PAINT ORANGE (-4900 4225);
DISPLAY INVISIBLE (-4900 4225);
FORCEPROP 1 LAST PATH I410
J 0
(-4902 4225);
DISPLAY 0.872340 (-4902 4225);
PAINT GREEN (-4902 4225);
DISPLAY INVISIBLE (-4902 4225);
FORCEPROP 1 LAST BODY_TYPE PLUMBING
J 0
(-4850 4175);
DISPLAY 2.276596 (-4850 4175);
PAINT GREEN (-4850 4175);
DISPLAY INVISIBLE (-4850 4175);
FORCEPROP 1 LAST HDL_TAP TRUE
J 0
(-4580 4095);
DISPLAY 2.276596 (-4580 4095);
PAINT GREEN (-4580 4095);
DISPLAY INVISIBLE (-4580 4095);
FORCEADD TAP..3
(-5100 4225);
FORCEPROP 3 LASTPIN (-5100 4175) SIG_NAME P3E_CPU0_PE1_SS_TXN<4>
J 0
(-5090 4185);
DISPLAY 0.659574 (-5090 4185);
PAINT MONO (-5090 4185);
DISPLAY INVISIBLE (-5090 4185);
FORCEPROP 1 LASTPIN (-5100 4175) BN 4
R 1
J 0
(-5107 4163);
DISPLAY 0.617021 (-5107 4163);
PAINT GREEN (-5107 4163);
FORCEPROP 2 LAST CDS_LIB mstr_standard
J 0
(-5100 4225);
PAINT ORANGE (-5100 4225);
DISPLAY INVISIBLE (-5100 4225);
FORCEPROP 1 LAST PATH I411
J 0
(-5102 4225);
DISPLAY 0.872340 (-5102 4225);
PAINT GREEN (-5102 4225);
DISPLAY INVISIBLE (-5102 4225);
FORCEPROP 1 LAST BODY_TYPE PLUMBING
J 0
(-5050 4175);
DISPLAY 2.276596 (-5050 4175);
PAINT GREEN (-5050 4175);
DISPLAY INVISIBLE (-5050 4175);
FORCEPROP 1 LAST HDL_TAP TRUE
J 0
(-4780 4095);
DISPLAY 2.276596 (-4780 4095);
PAINT GREEN (-4780 4095);
DISPLAY INVISIBLE (-4780 4095);
FORCEADD TAP..3
(-5300 4225);
FORCEPROP 3 LASTPIN (-5300 4175) SIG_NAME P3E_CPU0_PE1_SS_TXN<5>
J 0
(-5290 4185);
DISPLAY 0.659574 (-5290 4185);
PAINT MONO (-5290 4185);
DISPLAY INVISIBLE (-5290 4185);
FORCEPROP 1 LASTPIN (-5300 4175) BN 5
R 1
J 0
(-5307 4163);
DISPLAY 0.617021 (-5307 4163);
PAINT GREEN (-5307 4163);
FORCEPROP 2 LAST CDS_LIB mstr_standard
J 0
(-5300 4225);
PAINT ORANGE (-5300 4225);
DISPLAY INVISIBLE (-5300 4225);
FORCEPROP 1 LAST PATH I412
J 0
(-5302 4225);
DISPLAY 0.872340 (-5302 4225);
PAINT GREEN (-5302 4225);
DISPLAY INVISIBLE (-5302 4225);
FORCEPROP 1 LAST BODY_TYPE PLUMBING
J 0
(-5250 4175);
DISPLAY 2.276596 (-5250 4175);
PAINT GREEN (-5250 4175);
DISPLAY INVISIBLE (-5250 4175);
FORCEPROP 1 LAST HDL_TAP TRUE
J 0
(-4980 4095);
DISPLAY 2.276596 (-4980 4095);
PAINT GREEN (-4980 4095);
DISPLAY INVISIBLE (-4980 4095);
FORCEADD TAP..3
(-5500 4225);
FORCEPROP 3 LASTPIN (-5500 4175) SIG_NAME P3E_CPU0_PE1_SS_TXN<6>
J 0
(-5490 4185);
DISPLAY 0.659574 (-5490 4185);
PAINT MONO (-5490 4185);
DISPLAY INVISIBLE (-5490 4185);
FORCEPROP 1 LASTPIN (-5500 4175) BN 6
R 1
J 0
(-5507 4163);
DISPLAY 0.617021 (-5507 4163);
PAINT GREEN (-5507 4163);
FORCEPROP 2 LAST CDS_LIB mstr_standard
J 0
(-5500 4225);
PAINT ORANGE (-5500 4225);
DISPLAY INVISIBLE (-5500 4225);
FORCEPROP 1 LAST PATH I413
J 0
(-5502 4225);
DISPLAY 0.872340 (-5502 4225);
PAINT GREEN (-5502 4225);
DISPLAY INVISIBLE (-5502 4225);
FORCEPROP 1 LAST BODY_TYPE PLUMBING
J 0
(-5450 4175);
DISPLAY 2.276596 (-5450 4175);
PAINT GREEN (-5450 4175);
DISPLAY INVISIBLE (-5450 4175);
FORCEPROP 1 LAST HDL_TAP TRUE
J 0
(-5180 4095);
DISPLAY 2.276596 (-5180 4095);
PAINT GREEN (-5180 4095);
DISPLAY INVISIBLE (-5180 4095);
FORCEADD TAP..3
(-5700 4225);
FORCEPROP 3 LASTPIN (-5700 4175) SIG_NAME P3E_CPU0_PE1_SS_TXN<7>
J 0
(-5690 4185);
DISPLAY 0.659574 (-5690 4185);
PAINT MONO (-5690 4185);
DISPLAY INVISIBLE (-5690 4185);
FORCEPROP 1 LASTPIN (-5700 4175) BN 7
R 1
J 0
(-5707 4163);
DISPLAY 0.617021 (-5707 4163);
PAINT GREEN (-5707 4163);
FORCEPROP 2 LAST CDS_LIB mstr_standard
J 0
(-5700 4225);
PAINT ORANGE (-5700 4225);
DISPLAY INVISIBLE (-5700 4225);
FORCEPROP 1 LAST PATH I414
J 0
(-5702 4225);
DISPLAY 0.872340 (-5702 4225);
PAINT GREEN (-5702 4225);
DISPLAY INVISIBLE (-5702 4225);
FORCEPROP 1 LAST BODY_TYPE PLUMBING
J 0
(-5650 4175);
DISPLAY 2.276596 (-5650 4175);
PAINT GREEN (-5650 4175);
DISPLAY INVISIBLE (-5650 4175);
FORCEPROP 1 LAST HDL_TAP TRUE
J 0
(-5380 4095);
DISPLAY 2.276596 (-5380 4095);
PAINT GREEN (-5380 4095);
DISPLAY INVISIBLE (-5380 4095);
FORCEADD OFFPAGE..2
(-4050 3375);
FORCEPROP 2 LAST $XR0 109 
J 0
(-3861 3375);
DISPLAY 0.638298 (-3861 3375);
PAINT MONO (-3861 3375);
FORCEPROP 2 LAST CDS_LIB mstr_standard
J 0
(-4050 3375);
PAINT ORANGE (-4050 3375);
DISPLAY INVISIBLE (-4050 3375);
FORCEPROP 2 LAST PATH I416
J 0
(-3875 3450);
DISPLAY 1.021277 (-3875 3450);
PAINT ORANGE (-3875 3450);
DISPLAY INVISIBLE (-3875 3450);
FORCEPROP 1 LAST OFFPAGE TRUE
J 0
(-3725 3250);
DISPLAY 0.872340 (-3725 3250);
PAINT GREEN (-3725 3250);
DISPLAY INVISIBLE (-3725 3250);
FORCEPROP 1 LAST COMMENT_BODY TRUE
J 0
(-4095 3280);
DISPLAY 0.872340 (-4095 3280);
PAINT GREEN (-4095 3280);
DISPLAY INVISIBLE (-4095 3280);
FORCEADD TAP..7
(-4300 3425);
FORCEPROP 3 LASTPIN (-4300 3475) SIG_NAME P3E_CPU0_PE1_SS_C_TXN<0>
J 0
(-4290 3485);
DISPLAY 0.659574 (-4290 3485);
PAINT MONO (-4290 3485);
DISPLAY INVISIBLE (-4290 3485);
FORCEPROP 1 LASTPIN (-4300 3475) BN 0
R 1
J 0
(-4307 3423);
DISPLAY 0.617021 (-4307 3423);
PAINT GREEN (-4307 3423);
FORCEPROP 2 LAST CDS_LIB mstr_standard
J 0
(-4300 3425);
PAINT ORANGE (-4300 3425);
DISPLAY INVISIBLE (-4300 3425);
FORCEPROP 1 LAST PATH I418
J 0
(-4302 3425);
DISPLAY 0.872340 (-4302 3425);
PAINT GREEN (-4302 3425);
DISPLAY INVISIBLE (-4302 3425);
FORCEPROP 1 LAST BODY_TYPE PLUMBING
J 0
(-4250 3425);
DISPLAY 2.276596 (-4250 3425);
PAINT GREEN (-4250 3425);
DISPLAY INVISIBLE (-4250 3425);
FORCEPROP 1 LAST HDL_TAP TRUE
J 0
(-3980 3295);
DISPLAY 2.276596 (-3980 3295);
PAINT GREEN (-3980 3295);
DISPLAY INVISIBLE (-3980 3295);
FORCEADD TAP..3
(-4250 3225);
FORCEPROP 3 LASTPIN (-4250 3175) SIG_NAME P3E_CPU0_PE1_SS_TXP<0>
J 0
(-4240 3185);
DISPLAY 0.659574 (-4240 3185);
PAINT MONO (-4240 3185);
DISPLAY INVISIBLE (-4240 3185);
FORCEPROP 1 LASTPIN (-4250 3175) BN 0
R 1
J 0
(-4257 3163);
DISPLAY 0.617021 (-4257 3163);
PAINT GREEN (-4257 3163);
FORCEPROP 2 LAST CDS_LIB mstr_standard
J 0
(-4250 3225);
PAINT ORANGE (-4250 3225);
DISPLAY INVISIBLE (-4250 3225);
FORCEPROP 1 LAST PATH I419
J 0
(-4252 3225);
DISPLAY 0.872340 (-4252 3225);
PAINT GREEN (-4252 3225);
DISPLAY INVISIBLE (-4252 3225);
FORCEPROP 1 LAST BODY_TYPE PLUMBING
J 0
(-4200 3175);
DISPLAY 2.276596 (-4200 3175);
PAINT GREEN (-4200 3175);
DISPLAY INVISIBLE (-4200 3175);
FORCEPROP 1 LAST HDL_TAP TRUE
J 0
(-3930 3095);
DISPLAY 2.276596 (-3930 3095);
PAINT GREEN (-3930 3095);
DISPLAY INVISIBLE (-3930 3095);
FORCEADD TAP..3
(-4450 3225);
FORCEPROP 3 LASTPIN (-4450 3175) SIG_NAME P3E_CPU0_PE1_SS_TXP<1>
J 0
(-4440 3185);
DISPLAY 0.659574 (-4440 3185);
PAINT MONO (-4440 3185);
DISPLAY INVISIBLE (-4440 3185);
FORCEPROP 1 LASTPIN (-4450 3175) BN 1
R 1
J 0
(-4457 3163);
DISPLAY 0.617021 (-4457 3163);
PAINT GREEN (-4457 3163);
FORCEPROP 2 LAST CDS_LIB mstr_standard
J 0
(-4450 3225);
PAINT ORANGE (-4450 3225);
DISPLAY INVISIBLE (-4450 3225);
FORCEPROP 1 LAST PATH I420
J 0
(-4452 3225);
DISPLAY 0.872340 (-4452 3225);
PAINT GREEN (-4452 3225);
DISPLAY INVISIBLE (-4452 3225);
FORCEPROP 1 LAST BODY_TYPE PLUMBING
J 0
(-4400 3175);
DISPLAY 2.276596 (-4400 3175);
PAINT GREEN (-4400 3175);
DISPLAY INVISIBLE (-4400 3175);
FORCEPROP 1 LAST HDL_TAP TRUE
J 0
(-4130 3095);
DISPLAY 2.276596 (-4130 3095);
PAINT GREEN (-4130 3095);
DISPLAY INVISIBLE (-4130 3095);
FORCEADD TAP..7
(-4500 3425);
FORCEPROP 3 LASTPIN (-4500 3475) SIG_NAME P3E_CPU0_PE1_SS_C_TXN<1>
J 0
(-4490 3485);
DISPLAY 0.659574 (-4490 3485);
PAINT MONO (-4490 3485);
DISPLAY INVISIBLE (-4490 3485);
FORCEPROP 1 LASTPIN (-4500 3475) BN 1
R 1
J 0
(-4507 3423);
DISPLAY 0.617021 (-4507 3423);
PAINT GREEN (-4507 3423);
FORCEPROP 2 LAST CDS_LIB mstr_standard
J 0
(-4500 3425);
PAINT ORANGE (-4500 3425);
DISPLAY INVISIBLE (-4500 3425);
FORCEPROP 1 LAST PATH I421
J 0
(-4502 3425);
DISPLAY 0.872340 (-4502 3425);
PAINT GREEN (-4502 3425);
DISPLAY INVISIBLE (-4502 3425);
FORCEPROP 1 LAST BODY_TYPE PLUMBING
J 0
(-4450 3425);
DISPLAY 2.276596 (-4450 3425);
PAINT GREEN (-4450 3425);
DISPLAY INVISIBLE (-4450 3425);
FORCEPROP 1 LAST HDL_TAP TRUE
J 0
(-4180 3295);
DISPLAY 2.276596 (-4180 3295);
PAINT GREEN (-4180 3295);
DISPLAY INVISIBLE (-4180 3295);
FORCEADD TAP..3
(-4650 3225);
FORCEPROP 3 LASTPIN (-4650 3175) SIG_NAME P3E_CPU0_PE1_SS_TXP<2>
J 0
(-4640 3185);
DISPLAY 0.659574 (-4640 3185);
PAINT MONO (-4640 3185);
DISPLAY INVISIBLE (-4640 3185);
FORCEPROP 1 LASTPIN (-4650 3175) BN 2
R 1
J 0
(-4657 3163);
DISPLAY 0.617021 (-4657 3163);
PAINT GREEN (-4657 3163);
FORCEPROP 1 LAST PATH I425
J 0
(-4652 3225);
DISPLAY 0.872340 (-4652 3225);
PAINT GREEN (-4652 3225);
DISPLAY INVISIBLE (-4652 3225);
FORCEPROP 2 LAST CDS_LIB mstr_standard
J 0
(-4650 3225);
PAINT ORANGE (-4650 3225);
DISPLAY INVISIBLE (-4650 3225);
FORCEPROP 1 LAST BODY_TYPE PLUMBING
J 0
(-4600 3175);
DISPLAY 2.276596 (-4600 3175);
PAINT GREEN (-4600 3175);
DISPLAY INVISIBLE (-4600 3175);
FORCEPROP 1 LAST HDL_TAP TRUE
J 0
(-4330 3095);
DISPLAY 2.276596 (-4330 3095);
PAINT GREEN (-4330 3095);
DISPLAY INVISIBLE (-4330 3095);
FORCEADD TAP..7
(-4700 3425);
FORCEPROP 3 LASTPIN (-4700 3475) SIG_NAME P3E_CPU0_PE1_SS_C_TXN<2>
J 0
(-4690 3485);
DISPLAY 0.659574 (-4690 3485);
PAINT MONO (-4690 3485);
DISPLAY INVISIBLE (-4690 3485);
FORCEPROP 1 LASTPIN (-4700 3475) BN 2
R 1
J 0
(-4707 3423);
DISPLAY 0.617021 (-4707 3423);
PAINT GREEN (-4707 3423);
FORCEPROP 2 LAST CDS_LIB mstr_standard
J 0
(-4700 3425);
PAINT ORANGE (-4700 3425);
DISPLAY INVISIBLE (-4700 3425);
FORCEPROP 1 LAST PATH I426
J 0
(-4702 3425);
DISPLAY 0.872340 (-4702 3425);
PAINT GREEN (-4702 3425);
DISPLAY INVISIBLE (-4702 3425);
FORCEPROP 1 LAST BODY_TYPE PLUMBING
J 0
(-4650 3425);
DISPLAY 2.276596 (-4650 3425);
PAINT GREEN (-4650 3425);
DISPLAY INVISIBLE (-4650 3425);
FORCEPROP 1 LAST HDL_TAP TRUE
J 0
(-4380 3295);
DISPLAY 2.276596 (-4380 3295);
PAINT GREEN (-4380 3295);
DISPLAY INVISIBLE (-4380 3295);
FORCEADD TAP..3
(-4850 3225);
FORCEPROP 3 LASTPIN (-4850 3175) SIG_NAME P3E_CPU0_PE1_SS_TXP<3>
J 0
(-4840 3185);
DISPLAY 0.659574 (-4840 3185);
PAINT MONO (-4840 3185);
DISPLAY INVISIBLE (-4840 3185);
FORCEPROP 1 LASTPIN (-4850 3175) BN 3
R 1
J 0
(-4857 3163);
DISPLAY 0.617021 (-4857 3163);
PAINT GREEN (-4857 3163);
FORCEPROP 1 LAST PATH I428
J 0
(-4852 3225);
DISPLAY 0.872340 (-4852 3225);
PAINT GREEN (-4852 3225);
DISPLAY INVISIBLE (-4852 3225);
FORCEPROP 2 LAST CDS_LIB mstr_standard
J 0
(-4850 3225);
PAINT ORANGE (-4850 3225);
DISPLAY INVISIBLE (-4850 3225);
FORCEPROP 1 LAST BODY_TYPE PLUMBING
J 0
(-4800 3175);
DISPLAY 2.276596 (-4800 3175);
PAINT GREEN (-4800 3175);
DISPLAY INVISIBLE (-4800 3175);
FORCEPROP 1 LAST HDL_TAP TRUE
J 0
(-4530 3095);
DISPLAY 2.276596 (-4530 3095);
PAINT GREEN (-4530 3095);
DISPLAY INVISIBLE (-4530 3095);
FORCEADD TAP..7
(-4900 3425);
FORCEPROP 3 LASTPIN (-4900 3475) SIG_NAME P3E_CPU0_PE1_SS_C_TXN<3>
J 0
(-4890 3485);
DISPLAY 0.659574 (-4890 3485);
PAINT MONO (-4890 3485);
DISPLAY INVISIBLE (-4890 3485);
FORCEPROP 1 LASTPIN (-4900 3475) BN 3
R 1
J 0
(-4907 3423);
DISPLAY 0.617021 (-4907 3423);
PAINT GREEN (-4907 3423);
FORCEPROP 1 LAST PATH I429
J 0
(-4902 3425);
DISPLAY 0.872340 (-4902 3425);
PAINT GREEN (-4902 3425);
DISPLAY INVISIBLE (-4902 3425);
FORCEPROP 2 LAST CDS_LIB mstr_standard
J 0
(-4900 3425);
PAINT ORANGE (-4900 3425);
DISPLAY INVISIBLE (-4900 3425);
FORCEPROP 1 LAST BODY_TYPE PLUMBING
J 0
(-4850 3425);
DISPLAY 2.276596 (-4850 3425);
PAINT GREEN (-4850 3425);
DISPLAY INVISIBLE (-4850 3425);
FORCEPROP 1 LAST HDL_TAP TRUE
J 0
(-4580 3295);
DISPLAY 2.276596 (-4580 3295);
PAINT GREEN (-4580 3295);
DISPLAY INVISIBLE (-4580 3295);
FORCEADD TAP..7
(-4250 2425);
FORCEPROP 3 LASTPIN (-4250 2475) SIG_NAME P3E_CPU0_PE1_SS_C_TXP<0>
J 0
(-4240 2485);
DISPLAY 0.659574 (-4240 2485);
PAINT MONO (-4240 2485);
DISPLAY INVISIBLE (-4240 2485);
FORCEPROP 1 LASTPIN (-4250 2475) BN 0
R 1
J 0
(-4257 2423);
DISPLAY 0.617021 (-4257 2423);
PAINT GREEN (-4257 2423);
FORCEPROP 2 LAST CDS_LIB mstr_standard
J 0
(-4250 2425);
PAINT ORANGE (-4250 2425);
DISPLAY INVISIBLE (-4250 2425);
FORCEPROP 1 LAST PATH I430
J 0
(-4252 2425);
DISPLAY 0.872340 (-4252 2425);
PAINT GREEN (-4252 2425);
DISPLAY INVISIBLE (-4252 2425);
FORCEPROP 1 LAST BODY_TYPE PLUMBING
J 0
(-4200 2425);
DISPLAY 2.276596 (-4200 2425);
PAINT GREEN (-4200 2425);
DISPLAY INVISIBLE (-4200 2425);
FORCEPROP 1 LAST HDL_TAP TRUE
J 0
(-3930 2295);
DISPLAY 2.276596 (-3930 2295);
PAINT GREEN (-3930 2295);
DISPLAY INVISIBLE (-3930 2295);
FORCEADD TAP..7
(-4450 2425);
FORCEPROP 3 LASTPIN (-4450 2475) SIG_NAME P3E_CPU0_PE1_SS_C_TXP<1>
J 0
(-4440 2485);
DISPLAY 0.659574 (-4440 2485);
PAINT MONO (-4440 2485);
DISPLAY INVISIBLE (-4440 2485);
FORCEPROP 1 LASTPIN (-4450 2475) BN 1
R 1
J 0
(-4457 2423);
DISPLAY 0.617021 (-4457 2423);
PAINT GREEN (-4457 2423);
FORCEPROP 2 LAST CDS_LIB mstr_standard
J 0
(-4450 2425);
PAINT ORANGE (-4450 2425);
DISPLAY INVISIBLE (-4450 2425);
FORCEPROP 1 LAST PATH I432
J 0
(-4452 2425);
DISPLAY 0.872340 (-4452 2425);
PAINT GREEN (-4452 2425);
DISPLAY INVISIBLE (-4452 2425);
FORCEPROP 1 LAST BODY_TYPE PLUMBING
J 0
(-4400 2425);
DISPLAY 2.276596 (-4400 2425);
PAINT GREEN (-4400 2425);
DISPLAY INVISIBLE (-4400 2425);
FORCEPROP 1 LAST HDL_TAP TRUE
J 0
(-4130 2295);
DISPLAY 2.276596 (-4130 2295);
PAINT GREEN (-4130 2295);
DISPLAY INVISIBLE (-4130 2295);
FORCEADD OFFPAGE..2
(-4025 2375);
FORCEPROP 2 LAST $XR0 109 
J 0
(-3836 2375);
DISPLAY 0.638298 (-3836 2375);
PAINT MONO (-3836 2375);
FORCEPROP 2 LAST CDS_LIB mstr_standard
J 0
(-4025 2375);
PAINT ORANGE (-4025 2375);
DISPLAY INVISIBLE (-4025 2375);
FORCEPROP 2 LAST PATH I433
J 0
(-3850 2450);
DISPLAY 1.021277 (-3850 2450);
PAINT ORANGE (-3850 2450);
DISPLAY INVISIBLE (-3850 2450);
FORCEPROP 1 LAST OFFPAGE TRUE
J 0
(-3700 2250);
DISPLAY 0.872340 (-3700 2250);
PAINT GREEN (-3700 2250);
DISPLAY INVISIBLE (-3700 2250);
FORCEPROP 1 LAST COMMENT_BODY TRUE
J 0
(-4070 2280);
DISPLAY 0.872340 (-4070 2280);
PAINT GREEN (-4070 2280);
DISPLAY INVISIBLE (-4070 2280);
FORCEADD TAP..7
(-4650 2425);
FORCEPROP 3 LASTPIN (-4650 2475) SIG_NAME P3E_CPU0_PE1_SS_C_TXP<2>
J 0
(-4640 2485);
DISPLAY 0.659574 (-4640 2485);
PAINT MONO (-4640 2485);
DISPLAY INVISIBLE (-4640 2485);
FORCEPROP 1 LASTPIN (-4650 2475) BN 2
R 1
J 0
(-4657 2423);
DISPLAY 0.617021 (-4657 2423);
PAINT GREEN (-4657 2423);
FORCEPROP 2 LAST CDS_LIB mstr_standard
J 0
(-4650 2425);
PAINT ORANGE (-4650 2425);
DISPLAY INVISIBLE (-4650 2425);
FORCEPROP 1 LAST PATH I434
J 0
(-4652 2425);
DISPLAY 0.872340 (-4652 2425);
PAINT GREEN (-4652 2425);
DISPLAY INVISIBLE (-4652 2425);
FORCEPROP 1 LAST BODY_TYPE PLUMBING
J 0
(-4600 2425);
DISPLAY 2.276596 (-4600 2425);
PAINT GREEN (-4600 2425);
DISPLAY INVISIBLE (-4600 2425);
FORCEPROP 1 LAST HDL_TAP TRUE
J 0
(-4330 2295);
DISPLAY 2.276596 (-4330 2295);
PAINT GREEN (-4330 2295);
DISPLAY INVISIBLE (-4330 2295);
FORCEADD TAP..7
(-4850 2425);
FORCEPROP 3 LASTPIN (-4850 2475) SIG_NAME P3E_CPU0_PE1_SS_C_TXP<3>
J 0
(-4840 2485);
DISPLAY 0.659574 (-4840 2485);
PAINT MONO (-4840 2485);
DISPLAY INVISIBLE (-4840 2485);
FORCEPROP 1 LASTPIN (-4850 2475) BN 3
R 1
J 0
(-4857 2423);
DISPLAY 0.617021 (-4857 2423);
PAINT GREEN (-4857 2423);
FORCEPROP 2 LAST CDS_LIB mstr_standard
J 0
(-4850 2425);
PAINT ORANGE (-4850 2425);
DISPLAY INVISIBLE (-4850 2425);
FORCEPROP 1 LAST PATH I436
J 0
(-4852 2425);
DISPLAY 0.872340 (-4852 2425);
PAINT GREEN (-4852 2425);
DISPLAY INVISIBLE (-4852 2425);
FORCEPROP 1 LAST BODY_TYPE PLUMBING
J 0
(-4800 2425);
DISPLAY 2.276596 (-4800 2425);
PAINT GREEN (-4800 2425);
DISPLAY INVISIBLE (-4800 2425);
FORCEPROP 1 LAST HDL_TAP TRUE
J 0
(-4530 2295);
DISPLAY 2.276596 (-4530 2295);
PAINT GREEN (-4530 2295);
DISPLAY INVISIBLE (-4530 2295);
FORCEADD TAP..7
(-5100 3425);
FORCEPROP 3 LASTPIN (-5100 3475) SIG_NAME P3E_CPU0_PE1_SS_C_TXN<4>
J 0
(-5090 3485);
DISPLAY 0.659574 (-5090 3485);
PAINT MONO (-5090 3485);
DISPLAY INVISIBLE (-5090 3485);
FORCEPROP 1 LASTPIN (-5100 3475) BN 4
R 1
J 0
(-5107 3423);
DISPLAY 0.617021 (-5107 3423);
PAINT GREEN (-5107 3423);
FORCEPROP 2 LAST CDS_LIB mstr_standard
J 0
(-5100 3425);
PAINT ORANGE (-5100 3425);
DISPLAY INVISIBLE (-5100 3425);
FORCEPROP 1 LAST PATH I440
J 0
(-5102 3425);
DISPLAY 0.872340 (-5102 3425);
PAINT GREEN (-5102 3425);
DISPLAY INVISIBLE (-5102 3425);
FORCEPROP 1 LAST BODY_TYPE PLUMBING
J 0
(-5050 3425);
DISPLAY 2.276596 (-5050 3425);
PAINT GREEN (-5050 3425);
DISPLAY INVISIBLE (-5050 3425);
FORCEPROP 1 LAST HDL_TAP TRUE
J 0
(-4780 3295);
DISPLAY 2.276596 (-4780 3295);
PAINT GREEN (-4780 3295);
DISPLAY INVISIBLE (-4780 3295);
FORCEADD TAP..3
(-5050 3225);
FORCEPROP 3 LASTPIN (-5050 3175) SIG_NAME P3E_CPU0_PE1_SS_TXP<4>
J 0
(-5040 3185);
DISPLAY 0.659574 (-5040 3185);
PAINT MONO (-5040 3185);
DISPLAY INVISIBLE (-5040 3185);
FORCEPROP 1 LASTPIN (-5050 3175) BN 4
R 1
J 0
(-5057 3163);
DISPLAY 0.617021 (-5057 3163);
PAINT GREEN (-5057 3163);
FORCEPROP 2 LAST CDS_LIB mstr_standard
J 0
(-5050 3225);
PAINT ORANGE (-5050 3225);
DISPLAY INVISIBLE (-5050 3225);
FORCEPROP 1 LAST PATH I441
J 0
(-5052 3225);
DISPLAY 0.872340 (-5052 3225);
PAINT GREEN (-5052 3225);
DISPLAY INVISIBLE (-5052 3225);
FORCEPROP 1 LAST BODY_TYPE PLUMBING
J 0
(-5000 3175);
DISPLAY 2.276596 (-5000 3175);
PAINT GREEN (-5000 3175);
DISPLAY INVISIBLE (-5000 3175);
FORCEPROP 1 LAST HDL_TAP TRUE
J 0
(-4730 3095);
DISPLAY 2.276596 (-4730 3095);
PAINT GREEN (-4730 3095);
DISPLAY INVISIBLE (-4730 3095);
FORCEADD TAP..7
(-5300 3425);
FORCEPROP 3 LASTPIN (-5300 3475) SIG_NAME P3E_CPU0_PE1_SS_C_TXN<5>
J 0
(-5290 3485);
DISPLAY 0.659574 (-5290 3485);
PAINT MONO (-5290 3485);
DISPLAY INVISIBLE (-5290 3485);
FORCEPROP 1 LASTPIN (-5300 3475) BN 5
R 1
J 0
(-5307 3423);
DISPLAY 0.617021 (-5307 3423);
PAINT GREEN (-5307 3423);
FORCEPROP 2 LAST CDS_LIB mstr_standard
J 0
(-5300 3425);
PAINT ORANGE (-5300 3425);
DISPLAY INVISIBLE (-5300 3425);
FORCEPROP 1 LAST PATH I442
J 0
(-5302 3425);
DISPLAY 0.872340 (-5302 3425);
PAINT GREEN (-5302 3425);
DISPLAY INVISIBLE (-5302 3425);
FORCEPROP 1 LAST BODY_TYPE PLUMBING
J 0
(-5250 3425);
DISPLAY 2.276596 (-5250 3425);
PAINT GREEN (-5250 3425);
DISPLAY INVISIBLE (-5250 3425);
FORCEPROP 1 LAST HDL_TAP TRUE
J 0
(-4980 3295);
DISPLAY 2.276596 (-4980 3295);
PAINT GREEN (-4980 3295);
DISPLAY INVISIBLE (-4980 3295);
FORCEADD TAP..3
(-5250 3225);
FORCEPROP 3 LASTPIN (-5250 3175) SIG_NAME P3E_CPU0_PE1_SS_TXP<5>
J 0
(-5240 3185);
DISPLAY 0.659574 (-5240 3185);
PAINT MONO (-5240 3185);
DISPLAY INVISIBLE (-5240 3185);
FORCEPROP 1 LASTPIN (-5250 3175) BN 5
R 1
J 0
(-5257 3163);
DISPLAY 0.617021 (-5257 3163);
PAINT GREEN (-5257 3163);
FORCEPROP 2 LAST CDS_LIB mstr_standard
J 0
(-5250 3225);
PAINT ORANGE (-5250 3225);
DISPLAY INVISIBLE (-5250 3225);
FORCEPROP 1 LAST PATH I443
J 0
(-5252 3225);
DISPLAY 0.872340 (-5252 3225);
PAINT GREEN (-5252 3225);
DISPLAY INVISIBLE (-5252 3225);
FORCEPROP 1 LAST BODY_TYPE PLUMBING
J 0
(-5200 3175);
DISPLAY 2.276596 (-5200 3175);
PAINT GREEN (-5200 3175);
DISPLAY INVISIBLE (-5200 3175);
FORCEPROP 1 LAST HDL_TAP TRUE
J 0
(-4930 3095);
DISPLAY 2.276596 (-4930 3095);
PAINT GREEN (-4930 3095);
DISPLAY INVISIBLE (-4930 3095);
FORCEADD TAP..7
(-5500 3425);
FORCEPROP 3 LASTPIN (-5500 3475) SIG_NAME P3E_CPU0_PE1_SS_C_TXN<6>
J 0
(-5490 3485);
DISPLAY 0.659574 (-5490 3485);
PAINT MONO (-5490 3485);
DISPLAY INVISIBLE (-5490 3485);
FORCEPROP 1 LASTPIN (-5500 3475) BN 6
R 1
J 0
(-5507 3423);
DISPLAY 0.617021 (-5507 3423);
PAINT GREEN (-5507 3423);
FORCEPROP 2 LAST CDS_LIB mstr_standard
J 0
(-5500 3425);
PAINT ORANGE (-5500 3425);
DISPLAY INVISIBLE (-5500 3425);
FORCEPROP 1 LAST PATH I445
J 0
(-5502 3425);
DISPLAY 0.872340 (-5502 3425);
PAINT GREEN (-5502 3425);
DISPLAY INVISIBLE (-5502 3425);
FORCEPROP 1 LAST BODY_TYPE PLUMBING
J 0
(-5450 3425);
DISPLAY 2.276596 (-5450 3425);
PAINT GREEN (-5450 3425);
DISPLAY INVISIBLE (-5450 3425);
FORCEPROP 1 LAST HDL_TAP TRUE
J 0
(-5180 3295);
DISPLAY 2.276596 (-5180 3295);
PAINT GREEN (-5180 3295);
DISPLAY INVISIBLE (-5180 3295);
FORCEADD TAP..3
(-5450 3225);
FORCEPROP 3 LASTPIN (-5450 3175) SIG_NAME P3E_CPU0_PE1_SS_TXP<6>
J 0
(-5440 3185);
DISPLAY 0.659574 (-5440 3185);
PAINT MONO (-5440 3185);
DISPLAY INVISIBLE (-5440 3185);
FORCEPROP 1 LASTPIN (-5450 3175) BN 6
R 1
J 0
(-5457 3163);
DISPLAY 0.617021 (-5457 3163);
PAINT GREEN (-5457 3163);
FORCEPROP 1 LAST PATH I446
J 0
(-5452 3225);
DISPLAY 0.872340 (-5452 3225);
PAINT GREEN (-5452 3225);
DISPLAY INVISIBLE (-5452 3225);
FORCEPROP 2 LAST CDS_LIB mstr_standard
J 0
(-5450 3225);
PAINT ORANGE (-5450 3225);
DISPLAY INVISIBLE (-5450 3225);
FORCEPROP 1 LAST BODY_TYPE PLUMBING
J 0
(-5400 3175);
DISPLAY 2.276596 (-5400 3175);
PAINT GREEN (-5400 3175);
DISPLAY INVISIBLE (-5400 3175);
FORCEPROP 1 LAST HDL_TAP TRUE
J 0
(-5130 3095);
DISPLAY 2.276596 (-5130 3095);
PAINT GREEN (-5130 3095);
DISPLAY INVISIBLE (-5130 3095);
FORCEADD TAP..3
(-5650 3225);
FORCEPROP 3 LASTPIN (-5650 3175) SIG_NAME P3E_CPU0_PE1_SS_TXP<7>
J 0
(-5640 3185);
DISPLAY 0.659574 (-5640 3185);
PAINT MONO (-5640 3185);
DISPLAY INVISIBLE (-5640 3185);
FORCEPROP 1 LASTPIN (-5650 3175) BN 7
R 1
J 0
(-5657 3163);
DISPLAY 0.617021 (-5657 3163);
PAINT GREEN (-5657 3163);
FORCEPROP 2 LAST CDS_LIB mstr_standard
J 0
(-5650 3225);
PAINT ORANGE (-5650 3225);
DISPLAY INVISIBLE (-5650 3225);
FORCEPROP 1 LAST PATH I449
J 0
(-5652 3225);
DISPLAY 0.872340 (-5652 3225);
PAINT GREEN (-5652 3225);
DISPLAY INVISIBLE (-5652 3225);
FORCEPROP 1 LAST BODY_TYPE PLUMBING
J 0
(-5600 3175);
DISPLAY 2.276596 (-5600 3175);
PAINT GREEN (-5600 3175);
DISPLAY INVISIBLE (-5600 3175);
FORCEPROP 1 LAST HDL_TAP TRUE
J 0
(-5330 3095);
DISPLAY 2.276596 (-5330 3095);
PAINT GREEN (-5330 3095);
DISPLAY INVISIBLE (-5330 3095);
FORCEADD TAP..7
(-5700 3425);
FORCEPROP 3 LASTPIN (-5700 3475) SIG_NAME P3E_CPU0_PE1_SS_C_TXN<7>
J 0
(-5690 3485);
DISPLAY 0.659574 (-5690 3485);
PAINT MONO (-5690 3485);
DISPLAY INVISIBLE (-5690 3485);
FORCEPROP 1 LASTPIN (-5700 3475) BN 7
R 1
J 0
(-5707 3423);
DISPLAY 0.617021 (-5707 3423);
PAINT GREEN (-5707 3423);
FORCEPROP 2 LAST CDS_LIB mstr_standard
J 0
(-5700 3425);
PAINT ORANGE (-5700 3425);
DISPLAY INVISIBLE (-5700 3425);
FORCEPROP 1 LAST PATH I450
J 0
(-5702 3425);
DISPLAY 0.872340 (-5702 3425);
PAINT GREEN (-5702 3425);
DISPLAY INVISIBLE (-5702 3425);
FORCEPROP 1 LAST BODY_TYPE PLUMBING
J 0
(-5650 3425);
DISPLAY 2.276596 (-5650 3425);
PAINT GREEN (-5650 3425);
DISPLAY INVISIBLE (-5650 3425);
FORCEPROP 1 LAST HDL_TAP TRUE
J 0
(-5380 3295);
DISPLAY 2.276596 (-5380 3295);
PAINT GREEN (-5380 3295);
DISPLAY INVISIBLE (-5380 3295);
FORCEADD TAP..7
(-5050 2425);
FORCEPROP 3 LASTPIN (-5050 2475) SIG_NAME P3E_CPU0_PE1_SS_C_TXP<4>
J 0
(-5040 2485);
DISPLAY 0.659574 (-5040 2485);
PAINT MONO (-5040 2485);
DISPLAY INVISIBLE (-5040 2485);
FORCEPROP 1 LASTPIN (-5050 2475) BN 4
R 1
J 0
(-5057 2423);
DISPLAY 0.617021 (-5057 2423);
PAINT GREEN (-5057 2423);
FORCEPROP 2 LAST CDS_LIB mstr_standard
J 0
(-5050 2425);
PAINT ORANGE (-5050 2425);
DISPLAY INVISIBLE (-5050 2425);
FORCEPROP 1 LAST PATH I451
J 0
(-5052 2425);
DISPLAY 0.872340 (-5052 2425);
PAINT GREEN (-5052 2425);
DISPLAY INVISIBLE (-5052 2425);
FORCEPROP 1 LAST BODY_TYPE PLUMBING
J 0
(-5000 2425);
DISPLAY 2.276596 (-5000 2425);
PAINT GREEN (-5000 2425);
DISPLAY INVISIBLE (-5000 2425);
FORCEPROP 1 LAST HDL_TAP TRUE
J 0
(-4730 2295);
DISPLAY 2.276596 (-4730 2295);
PAINT GREEN (-4730 2295);
DISPLAY INVISIBLE (-4730 2295);
FORCEADD TAP..7
(-5250 2425);
FORCEPROP 3 LASTPIN (-5250 2475) SIG_NAME P3E_CPU0_PE1_SS_C_TXP<5>
J 0
(-5240 2485);
DISPLAY 0.659574 (-5240 2485);
PAINT MONO (-5240 2485);
DISPLAY INVISIBLE (-5240 2485);
FORCEPROP 1 LASTPIN (-5250 2475) BN 5
R 1
J 0
(-5257 2423);
DISPLAY 0.617021 (-5257 2423);
PAINT GREEN (-5257 2423);
FORCEPROP 2 LAST CDS_LIB mstr_standard
J 0
(-5250 2425);
PAINT ORANGE (-5250 2425);
DISPLAY INVISIBLE (-5250 2425);
FORCEPROP 1 LAST PATH I453
J 0
(-5252 2425);
DISPLAY 0.872340 (-5252 2425);
PAINT GREEN (-5252 2425);
DISPLAY INVISIBLE (-5252 2425);
FORCEPROP 1 LAST BODY_TYPE PLUMBING
J 0
(-5200 2425);
DISPLAY 2.276596 (-5200 2425);
PAINT GREEN (-5200 2425);
DISPLAY INVISIBLE (-5200 2425);
FORCEPROP 1 LAST HDL_TAP TRUE
J 0
(-4930 2295);
DISPLAY 2.276596 (-4930 2295);
PAINT GREEN (-4930 2295);
DISPLAY INVISIBLE (-4930 2295);
FORCEADD TAP..7
(-5650 2425);
FORCEPROP 3 LASTPIN (-5650 2475) SIG_NAME P3E_CPU0_PE1_SS_C_TXP<7>
J 0
(-5640 2485);
DISPLAY 0.659574 (-5640 2485);
PAINT MONO (-5640 2485);
DISPLAY INVISIBLE (-5640 2485);
FORCEPROP 1 LASTPIN (-5650 2475) BN 7
R 1
J 0
(-5657 2423);
DISPLAY 0.617021 (-5657 2423);
PAINT GREEN (-5657 2423);
FORCEPROP 1 LAST PATH I454
J 0
(-5652 2425);
DISPLAY 0.872340 (-5652 2425);
PAINT GREEN (-5652 2425);
DISPLAY INVISIBLE (-5652 2425);
FORCEPROP 2 LAST CDS_LIB mstr_standard
J 0
(-5650 2425);
PAINT ORANGE (-5650 2425);
DISPLAY INVISIBLE (-5650 2425);
FORCEPROP 1 LAST BODY_TYPE PLUMBING
J 0
(-5600 2425);
DISPLAY 2.276596 (-5600 2425);
PAINT GREEN (-5600 2425);
DISPLAY INVISIBLE (-5600 2425);
FORCEPROP 1 LAST HDL_TAP TRUE
J 0
(-5330 2295);
DISPLAY 2.276596 (-5330 2295);
PAINT GREEN (-5330 2295);
DISPLAY INVISIBLE (-5330 2295);
FORCEADD OFFPAGE..1
(-6000 4275);
FORCEPROP 2 LAST $XR1 107 
J 0
(-6341 4275);
DISPLAY 0.638298 (-6341 4275);
PAINT MONO (-6341 4275);
FORCEPROP 2 LAST $XR0 30 
J 0
(-6221 4275);
DISPLAY 0.638298 (-6221 4275);
PAINT MONO (-6221 4275);
FORCEPROP 2 LAST PATH I456
J 0
(-5950 4350);
DISPLAY 1.021277 (-5950 4350);
PAINT ORANGE (-5950 4350);
DISPLAY INVISIBLE (-5950 4350);
FORCEPROP 2 LAST CDS_LIB mstr_standard
J 0
(-6000 4275);
PAINT ORANGE (-6000 4275);
DISPLAY INVISIBLE (-6000 4275);
FORCEPROP 1 LAST OFFPAGE TRUE
J 0
(-5675 4150);
DISPLAY 0.872340 (-5675 4150);
PAINT GREEN (-5675 4150);
DISPLAY INVISIBLE (-5675 4150);
FORCEPROP 1 LAST COMMENT_BODY TRUE
J 0
(-5875 4175);
DISPLAY 0.872340 (-5875 4175);
PAINT GREEN (-5875 4175);
DISPLAY INVISIBLE (-5875 4175);
FORCEADD OFFPAGE..1
(-5950 3275);
FORCEPROP 2 LAST $XR1 107 
J 0
(-6321 3275);
DISPLAY 0.638298 (-6321 3275);
PAINT MONO (-6321 3275);
FORCEPROP 2 LAST $XR0 30 
J 0
(-6201 3275);
DISPLAY 0.638298 (-6201 3275);
PAINT MONO (-6201 3275);
FORCEPROP 2 LAST CDS_LIB mstr_standard
J 0
(-5950 3275);
PAINT ORANGE (-5950 3275);
DISPLAY INVISIBLE (-5950 3275);
FORCEPROP 2 LAST PATH I457
J 0
(-5900 3350);
DISPLAY 1.021277 (-5900 3350);
PAINT ORANGE (-5900 3350);
DISPLAY INVISIBLE (-5900 3350);
FORCEPROP 1 LAST OFFPAGE TRUE
J 0
(-5625 3150);
DISPLAY 0.872340 (-5625 3150);
PAINT GREEN (-5625 3150);
DISPLAY INVISIBLE (-5625 3150);
FORCEPROP 1 LAST COMMENT_BODY TRUE
J 0
(-5825 3175);
DISPLAY 0.872340 (-5825 3175);
PAINT GREEN (-5825 3175);
DISPLAY INVISIBLE (-5825 3175);
FORCEADD CAP..1
(-5700 3675);
FORCEPROP 0 LAST GROUP PCIE_RISER
J 0
(-5650 3425);
DISPLAY 0.638298 (-5650 3425);
PAINT BROWN (-5650 3425);
DISPLAY BOTH (-5650 3425);
FORCEPROP 1 LAST VOLTAGE 16V
J 0
(-5650 3675);
DISPLAY 0.638298 (-5650 3675);
PAINT SKYBLUE (-5650 3675);
FORCEPROP 1 LAST VALUE 0.22UF
J 0
(-5650 3725);
DISPLAY 0.638298 (-5650 3725);
PAINT SKYBLUE (-5650 3725);
FORCEPROP 1 LAST TOLERANCE 10%
J 0
(-5650 3625);
DISPLAY 0.638298 (-5650 3625);
PAINT SKYBLUE (-5650 3625);
FORCEPROP 1 LAST PACK_TYPE 0402
J 0
(-5650 3475);
DISPLAY 0.638298 (-5650 3475);
PAINT SKYBLUE (-5650 3475);
FORCEPROP 1 LAST PART_NUMBER A36096-155
J 0
(-5650 3525);
DISPLAY 0.638298 (-5650 3525);
PAINT BLUE (-5650 3525);
FORCEPROP 1 LAST MATERIAL X7R
J 0
(-5650 3575);
DISPLAY 0.638298 (-5650 3575);
PAINT SKYBLUE (-5650 3575);
FORCEPROP 1 LAST LOCATION C3P41
J 0
(-5650 3775);
DISPLAY 0.638298 (-5650 3775);
PAINT SKYBLUE (-5650 3775);
FORCEPROP 2 LAST CDS_LIB mstr_discrete
J 0
(-5700 3675);
PAINT MONO (-5700 3675);
DISPLAY INVISIBLE (-5700 3675);
FORCEPROP 1 LAST PATH I474
J 0
(-5650 3825);
DISPLAY 0.978723 (-5650 3825);
PAINT WHITE (-5650 3825);
DISPLAY INVISIBLE (-5650 3825);
FORCEPROP 1 LASTPIN (-5700 3575) $PN 2
J 0
(-5690 3555);
DISPLAY 0.787234 (-5690 3555);
PAINT ORANGE (-5690 3555);
DISPLAY INVISIBLE (-5690 3555);
FORCEPROP 1 LASTPIN (-5700 3775) $PN 1
J 0
(-5690 3755);
DISPLAY 0.787234 (-5690 3755);
PAINT ORANGE (-5690 3755);
DISPLAY INVISIBLE (-5690 3755);
FORCEADD CAP..1
(-5500 3975);
FORCEPROP 0 LAST GROUP PCIE_RISER
J 0
(-5450 4125);
DISPLAY 0.638298 (-5450 4125);
PAINT BROWN (-5450 4125);
DISPLAY BOTH (-5450 4125);
FORCEPROP 1 LAST VOLTAGE 16V
J 0
(-5450 3975);
DISPLAY 0.638298 (-5450 3975);
PAINT SKYBLUE (-5450 3975);
FORCEPROP 1 LAST TOLERANCE 10%
J 0
(-5450 3925);
DISPLAY 0.638298 (-5450 3925);
PAINT SKYBLUE (-5450 3925);
FORCEPROP 1 LAST PACK_TYPE 0402
J 0
(-5450 3775);
DISPLAY 0.638298 (-5450 3775);
PAINT SKYBLUE (-5450 3775);
FORCEPROP 1 LAST MATERIAL X7R
J 0
(-5450 3875);
DISPLAY 0.638298 (-5450 3875);
PAINT SKYBLUE (-5450 3875);
FORCEPROP 1 LAST VALUE 0.22UF
J 0
(-5450 4025);
DISPLAY 0.638298 (-5450 4025);
PAINT SKYBLUE (-5450 4025);
FORCEPROP 1 LAST LOCATION C3P36
J 0
(-5450 4075);
DISPLAY 0.638298 (-5450 4075);
PAINT SKYBLUE (-5450 4075);
FORCEPROP 1 LAST PART_NUMBER A36096-155
J 0
(-5450 3825);
DISPLAY 0.638298 (-5450 3825);
PAINT BLUE (-5450 3825);
FORCEPROP 2 LAST CDS_LIB mstr_discrete
J 0
(-5500 3975);
PAINT MONO (-5500 3975);
DISPLAY INVISIBLE (-5500 3975);
FORCEPROP 1 LAST PATH I475
J 0
(-5450 4125);
DISPLAY 0.978723 (-5450 4125);
PAINT WHITE (-5450 4125);
DISPLAY INVISIBLE (-5450 4125);
FORCEPROP 1 LASTPIN (-5500 3875) $PN 2
J 0
(-5490 3855);
DISPLAY 0.787234 (-5490 3855);
PAINT ORANGE (-5490 3855);
DISPLAY INVISIBLE (-5490 3855);
FORCEPROP 1 LASTPIN (-5500 4075) $PN 1
J 0
(-5490 4055);
DISPLAY 0.787234 (-5490 4055);
PAINT ORANGE (-5490 4055);
DISPLAY INVISIBLE (-5490 4055);
FORCEADD CAP..1
(-4500 3700);
FORCEPROP 1 LAST VALUE 0.22UF
J 0
(-4450 3750);
DISPLAY 0.638298 (-4450 3750);
PAINT SKYBLUE (-4450 3750);
FORCEPROP 1 LAST MATERIAL X7R
J 0
(-4450 3600);
DISPLAY 0.638298 (-4450 3600);
PAINT SKYBLUE (-4450 3600);
FORCEPROP 1 LAST PART_NUMBER A36096-155
J 0
(-4450 3550);
DISPLAY 0.638298 (-4450 3550);
PAINT BLUE (-4450 3550);
FORCEPROP 1 LAST PACK_TYPE 0402
J 0
(-4450 3500);
DISPLAY 0.638298 (-4450 3500);
PAINT SKYBLUE (-4450 3500);
FORCEPROP 0 LAST GROUP PCIE_RISER
J 0
(-4450 3450);
DISPLAY 0.638298 (-4450 3450);
PAINT BROWN (-4450 3450);
DISPLAY BOTH (-4450 3450);
FORCEPROP 1 LAST VOLTAGE 16V
J 0
(-4450 3700);
DISPLAY 0.638298 (-4450 3700);
PAINT SKYBLUE (-4450 3700);
FORCEPROP 1 LAST TOLERANCE 10%
J 0
(-4450 3650);
DISPLAY 0.638298 (-4450 3650);
PAINT SKYBLUE (-4450 3650);
FORCEPROP 1 LAST LOCATION C3P16
J 0
(-4450 3800);
DISPLAY 0.638298 (-4450 3800);
PAINT SKYBLUE (-4450 3800);
FORCEPROP 2 LAST CDS_LIB mstr_discrete
J 0
(-4500 3700);
PAINT MONO (-4500 3700);
DISPLAY INVISIBLE (-4500 3700);
FORCEPROP 1 LAST PATH I476
J 0
(-4450 3850);
DISPLAY 0.978723 (-4450 3850);
PAINT WHITE (-4450 3850);
DISPLAY INVISIBLE (-4450 3850);
FORCEPROP 1 LASTPIN (-4500 3600) $PN 2
J 0
(-4490 3580);
DISPLAY 0.787234 (-4490 3580);
PAINT ORANGE (-4490 3580);
DISPLAY INVISIBLE (-4490 3580);
FORCEPROP 1 LASTPIN (-4500 3800) $PN 1
J 0
(-4490 3780);
DISPLAY 0.787234 (-4490 3780);
PAINT ORANGE (-4490 3780);
DISPLAY INVISIBLE (-4490 3780);
FORCEADD CAP..1
(-5300 3675);
FORCEPROP 0 LAST GROUP PCIE_RISER
J 0
(-5250 3425);
DISPLAY 0.638298 (-5250 3425);
PAINT BROWN (-5250 3425);
DISPLAY BOTH (-5250 3425);
FORCEPROP 1 LAST PART_NUMBER A36096-155
J 0
(-5250 3525);
DISPLAY 0.638298 (-5250 3525);
PAINT BLUE (-5250 3525);
FORCEPROP 1 LAST VALUE 0.22UF
J 0
(-5250 3725);
DISPLAY 0.638298 (-5250 3725);
PAINT SKYBLUE (-5250 3725);
FORCEPROP 1 LAST VOLTAGE 16V
J 0
(-5250 3675);
DISPLAY 0.638298 (-5250 3675);
PAINT SKYBLUE (-5250 3675);
FORCEPROP 1 LAST TOLERANCE 10%
J 0
(-5250 3625);
DISPLAY 0.638298 (-5250 3625);
PAINT SKYBLUE (-5250 3625);
FORCEPROP 1 LAST PACK_TYPE 0402
J 0
(-5250 3475);
DISPLAY 0.638298 (-5250 3475);
PAINT SKYBLUE (-5250 3475);
FORCEPROP 1 LAST LOCATION C3P33
J 0
(-5250 3775);
DISPLAY 0.638298 (-5250 3775);
PAINT SKYBLUE (-5250 3775);
FORCEPROP 1 LAST MATERIAL X7R
J 0
(-5250 3575);
DISPLAY 0.638298 (-5250 3575);
PAINT SKYBLUE (-5250 3575);
FORCEPROP 1 LAST PATH I477
J 0
(-5250 3825);
DISPLAY 0.978723 (-5250 3825);
PAINT WHITE (-5250 3825);
DISPLAY INVISIBLE (-5250 3825);
FORCEPROP 2 LAST CDS_LIB mstr_discrete
J 0
(-5300 3675);
PAINT MONO (-5300 3675);
DISPLAY INVISIBLE (-5300 3675);
FORCEPROP 1 LASTPIN (-5300 3575) $PN 2
J 0
(-5290 3555);
DISPLAY 0.787234 (-5290 3555);
PAINT ORANGE (-5290 3555);
DISPLAY INVISIBLE (-5290 3555);
FORCEPROP 1 LASTPIN (-5300 3775) $PN 1
J 0
(-5290 3755);
DISPLAY 0.787234 (-5290 3755);
PAINT ORANGE (-5290 3755);
DISPLAY INVISIBLE (-5290 3755);
FORCEADD CAP..1
(-5100 3975);
FORCEPROP 0 LAST GROUP PCIE_RISER
J 0
(-5050 4125);
DISPLAY 0.638298 (-5050 4125);
PAINT BROWN (-5050 4125);
DISPLAY BOTH (-5050 4125);
FORCEPROP 1 LAST TOLERANCE 10%
J 0
(-5050 3925);
DISPLAY 0.638298 (-5050 3925);
PAINT SKYBLUE (-5050 3925);
FORCEPROP 1 LAST VALUE 0.22UF
J 0
(-5050 4025);
DISPLAY 0.638298 (-5050 4025);
PAINT SKYBLUE (-5050 4025);
FORCEPROP 1 LAST VOLTAGE 16V
J 0
(-5050 3975);
DISPLAY 0.638298 (-5050 3975);
PAINT SKYBLUE (-5050 3975);
FORCEPROP 1 LAST MATERIAL X7R
J 0
(-5050 3875);
DISPLAY 0.638298 (-5050 3875);
PAINT SKYBLUE (-5050 3875);
FORCEPROP 1 LAST PACK_TYPE 0402
J 0
(-5050 3775);
DISPLAY 0.638298 (-5050 3775);
PAINT SKYBLUE (-5050 3775);
FORCEPROP 1 LAST LOCATION C3P29
J 0
(-5050 4075);
DISPLAY 0.638298 (-5050 4075);
PAINT SKYBLUE (-5050 4075);
FORCEPROP 1 LAST PART_NUMBER A36096-155
J 0
(-5050 3825);
DISPLAY 0.638298 (-5050 3825);
PAINT BLUE (-5050 3825);
FORCEPROP 1 LAST PATH I478
J 0
(-5050 4125);
DISPLAY 0.978723 (-5050 4125);
PAINT WHITE (-5050 4125);
DISPLAY INVISIBLE (-5050 4125);
FORCEPROP 2 LAST CDS_LIB mstr_discrete
J 0
(-5100 3975);
PAINT MONO (-5100 3975);
DISPLAY INVISIBLE (-5100 3975);
FORCEPROP 1 LASTPIN (-5100 3875) $PN 2
J 0
(-5090 3855);
DISPLAY 0.787234 (-5090 3855);
PAINT ORANGE (-5090 3855);
DISPLAY INVISIBLE (-5090 3855);
FORCEPROP 1 LASTPIN (-5100 4075) $PN 1
J 0
(-5090 4055);
DISPLAY 0.787234 (-5090 4055);
PAINT ORANGE (-5090 4055);
DISPLAY INVISIBLE (-5090 4055);
FORCEADD CAP..1
(-4900 3675);
FORCEPROP 0 LAST GROUP PCIE_RISER
J 0
(-4850 3425);
DISPLAY 0.638298 (-4850 3425);
PAINT BROWN (-4850 3425);
DISPLAY BOTH (-4850 3425);
FORCEPROP 1 LAST LOCATION C3P24
J 0
(-4850 3775);
DISPLAY 0.638298 (-4850 3775);
PAINT SKYBLUE (-4850 3775);
FORCEPROP 1 LAST VALUE 0.22UF
J 0
(-4850 3725);
DISPLAY 0.638298 (-4850 3725);
PAINT SKYBLUE (-4850 3725);
FORCEPROP 1 LAST VOLTAGE 16V
J 0
(-4850 3675);
DISPLAY 0.638298 (-4850 3675);
PAINT SKYBLUE (-4850 3675);
FORCEPROP 1 LAST TOLERANCE 10%
J 0
(-4850 3625);
DISPLAY 0.638298 (-4850 3625);
PAINT SKYBLUE (-4850 3625);
FORCEPROP 1 LAST MATERIAL X7R
J 0
(-4850 3575);
DISPLAY 0.638298 (-4850 3575);
PAINT SKYBLUE (-4850 3575);
FORCEPROP 1 LAST PART_NUMBER A36096-155
J 0
(-4850 3525);
DISPLAY 0.638298 (-4850 3525);
PAINT BLUE (-4850 3525);
FORCEPROP 1 LAST PACK_TYPE 0402
J 0
(-4850 3475);
DISPLAY 0.638298 (-4850 3475);
PAINT SKYBLUE (-4850 3475);
FORCEPROP 1 LAST PATH I479
J 0
(-4850 3825);
DISPLAY 0.978723 (-4850 3825);
PAINT WHITE (-4850 3825);
DISPLAY INVISIBLE (-4850 3825);
FORCEPROP 2 LAST CDS_LIB mstr_discrete
J 0
(-4900 3675);
PAINT MONO (-4900 3675);
DISPLAY INVISIBLE (-4900 3675);
FORCEPROP 1 LASTPIN (-4900 3575) $PN 2
J 0
(-4890 3555);
DISPLAY 0.787234 (-4890 3555);
PAINT ORANGE (-4890 3555);
DISPLAY INVISIBLE (-4890 3555);
FORCEPROP 1 LASTPIN (-4900 3775) $PN 1
J 0
(-4890 3755);
DISPLAY 0.787234 (-4890 3755);
PAINT ORANGE (-4890 3755);
DISPLAY INVISIBLE (-4890 3755);
FORCEADD CAP..1
(-4700 3975);
FORCEPROP 1 LAST LOCATION C3P21
J 0
(-4650 4075);
DISPLAY 0.638298 (-4650 4075);
PAINT SKYBLUE (-4650 4075);
FORCEPROP 0 LAST GROUP PCIE_RISER
J 0
(-4650 4125);
DISPLAY 0.638298 (-4650 4125);
PAINT BROWN (-4650 4125);
DISPLAY BOTH (-4650 4125);
FORCEPROP 1 LAST PART_NUMBER A36096-155
J 0
(-4650 3825);
DISPLAY 0.638298 (-4650 3825);
PAINT BLUE (-4650 3825);
FORCEPROP 1 LAST MATERIAL X7R
J 0
(-4650 3875);
DISPLAY 0.638298 (-4650 3875);
PAINT SKYBLUE (-4650 3875);
FORCEPROP 1 LAST PACK_TYPE 0402
J 0
(-4650 3775);
DISPLAY 0.638298 (-4650 3775);
PAINT SKYBLUE (-4650 3775);
FORCEPROP 1 LAST VALUE 0.22UF
J 0
(-4650 4025);
DISPLAY 0.638298 (-4650 4025);
PAINT SKYBLUE (-4650 4025);
FORCEPROP 1 LAST VOLTAGE 16V
J 0
(-4650 3975);
DISPLAY 0.638298 (-4650 3975);
PAINT SKYBLUE (-4650 3975);
FORCEPROP 1 LAST TOLERANCE 10%
J 0
(-4650 3925);
DISPLAY 0.638298 (-4650 3925);
PAINT SKYBLUE (-4650 3925);
FORCEPROP 1 LAST PATH I480
J 0
(-4650 4125);
DISPLAY 0.978723 (-4650 4125);
PAINT WHITE (-4650 4125);
DISPLAY INVISIBLE (-4650 4125);
FORCEPROP 2 LAST CDS_LIB mstr_discrete
J 0
(-4700 3975);
PAINT MONO (-4700 3975);
DISPLAY INVISIBLE (-4700 3975);
FORCEPROP 1 LASTPIN (-4700 3875) $PN 2
J 0
(-4690 3855);
DISPLAY 0.787234 (-4690 3855);
PAINT ORANGE (-4690 3855);
DISPLAY INVISIBLE (-4690 3855);
FORCEPROP 1 LASTPIN (-4700 4075) $PN 1
J 0
(-4690 4055);
DISPLAY 0.787234 (-4690 4055);
PAINT ORANGE (-4690 4055);
DISPLAY INVISIBLE (-4690 4055);
FORCEADD CAP..1
(-4300 3975);
FORCEPROP 0 LAST GROUP PCIE_RISER
J 0
(-4250 4125);
DISPLAY 0.638298 (-4250 4125);
PAINT BROWN (-4250 4125);
DISPLAY BOTH (-4250 4125);
FORCEPROP 1 LAST VALUE 0.22UF
J 0
(-4250 4025);
DISPLAY 0.638298 (-4250 4025);
PAINT SKYBLUE (-4250 4025);
FORCEPROP 1 LAST TOLERANCE 10%
J 0
(-4250 3925);
DISPLAY 0.638298 (-4250 3925);
PAINT SKYBLUE (-4250 3925);
FORCEPROP 1 LAST MATERIAL X7R
J 0
(-4250 3875);
DISPLAY 0.638298 (-4250 3875);
PAINT SKYBLUE (-4250 3875);
FORCEPROP 1 LAST PART_NUMBER A36096-155
J 0
(-4250 3825);
DISPLAY 0.638298 (-4250 3825);
PAINT BLUE (-4250 3825);
FORCEPROP 1 LAST PACK_TYPE 0402
J 0
(-4250 3775);
DISPLAY 0.638298 (-4250 3775);
PAINT SKYBLUE (-4250 3775);
FORCEPROP 1 LAST VOLTAGE 16V
J 0
(-4250 3975);
DISPLAY 0.638298 (-4250 3975);
PAINT SKYBLUE (-4250 3975);
FORCEPROP 1 LAST LOCATION C3P12
J 0
(-4250 4075);
DISPLAY 0.638298 (-4250 4075);
PAINT SKYBLUE (-4250 4075);
FORCEPROP 2 LAST CDS_LIB mstr_discrete
J 0
(-4300 3975);
PAINT MONO (-4300 3975);
DISPLAY INVISIBLE (-4300 3975);
FORCEPROP 1 LAST PATH I481
J 0
(-4250 4125);
DISPLAY 0.978723 (-4250 4125);
PAINT WHITE (-4250 4125);
DISPLAY INVISIBLE (-4250 4125);
FORCEPROP 1 LASTPIN (-4300 3875) $PN 2
J 0
(-4290 3855);
DISPLAY 0.787234 (-4290 3855);
PAINT ORANGE (-4290 3855);
DISPLAY INVISIBLE (-4290 3855);
FORCEPROP 1 LASTPIN (-4300 4075) $PN 1
J 0
(-4290 4055);
DISPLAY 0.787234 (-4290 4055);
PAINT ORANGE (-4290 4055);
DISPLAY INVISIBLE (-4290 4055);
FORCEADD CAP..1
(-4250 2975);
FORCEPROP 0 LAST GROUP PCIE_RISER
J 0
(-4200 2725);
DISPLAY 0.638298 (-4200 2725);
PAINT BROWN (-4200 2725);
DISPLAY BOTH (-4200 2725);
FORCEPROP 1 LAST LOCATION C3P10
J 0
(-4200 3075);
DISPLAY 0.638298 (-4200 3075);
PAINT SKYBLUE (-4200 3075);
FORCEPROP 1 LAST VALUE 0.22UF
J 0
(-4200 3025);
DISPLAY 0.638298 (-4200 3025);
PAINT SKYBLUE (-4200 3025);
FORCEPROP 1 LAST MATERIAL X7R
J 0
(-4200 2875);
DISPLAY 0.638298 (-4200 2875);
PAINT SKYBLUE (-4200 2875);
FORCEPROP 1 LAST TOLERANCE 10%
J 0
(-4200 2925);
DISPLAY 0.638298 (-4200 2925);
PAINT SKYBLUE (-4200 2925);
FORCEPROP 1 LAST VOLTAGE 16V
J 0
(-4200 2975);
DISPLAY 0.638298 (-4200 2975);
PAINT SKYBLUE (-4200 2975);
FORCEPROP 1 LAST PACK_TYPE 0402
J 0
(-4200 2775);
DISPLAY 0.638298 (-4200 2775);
PAINT SKYBLUE (-4200 2775);
FORCEPROP 1 LAST PART_NUMBER A36096-155
J 0
(-4200 2825);
DISPLAY 0.638298 (-4200 2825);
PAINT BLUE (-4200 2825);
FORCEPROP 1 LAST PATH I482
J 0
(-4200 3125);
DISPLAY 0.978723 (-4200 3125);
PAINT WHITE (-4200 3125);
DISPLAY INVISIBLE (-4200 3125);
FORCEPROP 2 LAST CDS_LIB mstr_discrete
J 0
(-4250 2975);
PAINT MONO (-4250 2975);
DISPLAY INVISIBLE (-4250 2975);
FORCEPROP 1 LASTPIN (-4250 2875) $PN 2
J 0
(-4240 2855);
DISPLAY 0.787234 (-4240 2855);
PAINT ORANGE (-4240 2855);
DISPLAY INVISIBLE (-4240 2855);
FORCEPROP 1 LASTPIN (-4250 3075) $PN 1
J 0
(-4240 3055);
DISPLAY 0.787234 (-4240 3055);
PAINT ORANGE (-4240 3055);
DISPLAY INVISIBLE (-4240 3055);
FORCEADD CAP..1
(-4450 2675);
FORCEPROP 0 LAST GROUP PCIE_RISER
J 0
(-4400 2425);
DISPLAY 0.638298 (-4400 2425);
PAINT BROWN (-4400 2425);
DISPLAY BOTH (-4400 2425);
FORCEPROP 1 LAST LOCATION C3P14
J 0
(-4400 2775);
DISPLAY 0.638298 (-4400 2775);
PAINT SKYBLUE (-4400 2775);
FORCEPROP 1 LAST VALUE 0.22UF
J 0
(-4400 2725);
DISPLAY 0.638298 (-4400 2725);
PAINT SKYBLUE (-4400 2725);
FORCEPROP 1 LAST VOLTAGE 16V
J 0
(-4400 2675);
DISPLAY 0.638298 (-4400 2675);
PAINT SKYBLUE (-4400 2675);
FORCEPROP 1 LAST PART_NUMBER A36096-155
J 0
(-4400 2525);
DISPLAY 0.638298 (-4400 2525);
PAINT BLUE (-4400 2525);
FORCEPROP 1 LAST PACK_TYPE 0402
J 0
(-4400 2475);
DISPLAY 0.638298 (-4400 2475);
PAINT SKYBLUE (-4400 2475);
FORCEPROP 1 LAST MATERIAL X7R
J 0
(-4400 2575);
DISPLAY 0.638298 (-4400 2575);
PAINT SKYBLUE (-4400 2575);
FORCEPROP 1 LAST TOLERANCE 10%
J 0
(-4400 2625);
DISPLAY 0.638298 (-4400 2625);
PAINT SKYBLUE (-4400 2625);
FORCEPROP 2 LAST CDS_LIB mstr_discrete
J 0
(-4450 2675);
PAINT MONO (-4450 2675);
DISPLAY INVISIBLE (-4450 2675);
FORCEPROP 1 LAST PATH I483
J 0
(-4400 2825);
DISPLAY 0.978723 (-4400 2825);
PAINT WHITE (-4400 2825);
DISPLAY INVISIBLE (-4400 2825);
FORCEPROP 1 LASTPIN (-4450 2575) $PN 2
J 0
(-4440 2555);
DISPLAY 0.787234 (-4440 2555);
PAINT ORANGE (-4440 2555);
DISPLAY INVISIBLE (-4440 2555);
FORCEPROP 1 LASTPIN (-4450 2775) $PN 1
J 0
(-4440 2755);
DISPLAY 0.787234 (-4440 2755);
PAINT ORANGE (-4440 2755);
DISPLAY INVISIBLE (-4440 2755);
FORCEADD CAP..1
(-4850 2675);
FORCEPROP 0 LAST GROUP PCIE_RISER
J 0
(-4800 2425);
DISPLAY 0.638298 (-4800 2425);
PAINT BROWN (-4800 2425);
DISPLAY BOTH (-4800 2425);
FORCEPROP 1 LAST MATERIAL X7R
J 0
(-4800 2575);
DISPLAY 0.638298 (-4800 2575);
PAINT SKYBLUE (-4800 2575);
FORCEPROP 1 LAST VALUE 0.22UF
J 0
(-4800 2725);
DISPLAY 0.638298 (-4800 2725);
PAINT SKYBLUE (-4800 2725);
FORCEPROP 1 LAST LOCATION C3P22
J 0
(-4800 2775);
DISPLAY 0.638298 (-4800 2775);
PAINT SKYBLUE (-4800 2775);
FORCEPROP 1 LAST VOLTAGE 16V
J 0
(-4800 2675);
DISPLAY 0.638298 (-4800 2675);
PAINT SKYBLUE (-4800 2675);
FORCEPROP 1 LAST TOLERANCE 10%
J 0
(-4800 2625);
DISPLAY 0.638298 (-4800 2625);
PAINT SKYBLUE (-4800 2625);
FORCEPROP 1 LAST PACK_TYPE 0402
J 0
(-4800 2475);
DISPLAY 0.638298 (-4800 2475);
PAINT SKYBLUE (-4800 2475);
FORCEPROP 1 LAST PART_NUMBER A36096-155
J 0
(-4800 2525);
DISPLAY 0.638298 (-4800 2525);
PAINT BLUE (-4800 2525);
FORCEPROP 1 LAST PATH I484
J 0
(-4800 2825);
DISPLAY 0.978723 (-4800 2825);
PAINT WHITE (-4800 2825);
DISPLAY INVISIBLE (-4800 2825);
FORCEPROP 2 LAST CDS_LIB mstr_discrete
J 0
(-4850 2675);
PAINT MONO (-4850 2675);
DISPLAY INVISIBLE (-4850 2675);
FORCEPROP 1 LASTPIN (-4850 2575) $PN 2
J 0
(-4840 2555);
DISPLAY 0.787234 (-4840 2555);
PAINT ORANGE (-4840 2555);
DISPLAY INVISIBLE (-4840 2555);
FORCEPROP 1 LASTPIN (-4850 2775) $PN 1
J 0
(-4840 2755);
DISPLAY 0.787234 (-4840 2755);
PAINT ORANGE (-4840 2755);
DISPLAY INVISIBLE (-4840 2755);
FORCEADD CAP..1
(-4650 2975);
FORCEPROP 0 LAST GROUP PCIE_RISER
J 0
(-4600 3125);
DISPLAY 0.638298 (-4600 3125);
PAINT BROWN (-4600 3125);
DISPLAY BOTH (-4600 3125);
FORCEPROP 1 LAST LOCATION C3P19
J 0
(-4600 3075);
DISPLAY 0.638298 (-4600 3075);
PAINT SKYBLUE (-4600 3075);
FORCEPROP 1 LAST VALUE 0.22UF
J 0
(-4600 3025);
DISPLAY 0.638298 (-4600 3025);
PAINT SKYBLUE (-4600 3025);
FORCEPROP 1 LAST MATERIAL X7R
J 0
(-4600 2875);
DISPLAY 0.638298 (-4600 2875);
PAINT SKYBLUE (-4600 2875);
FORCEPROP 1 LAST TOLERANCE 10%
J 0
(-4600 2925);
DISPLAY 0.638298 (-4600 2925);
PAINT SKYBLUE (-4600 2925);
FORCEPROP 1 LAST VOLTAGE 16V
J 0
(-4600 2975);
DISPLAY 0.638298 (-4600 2975);
PAINT SKYBLUE (-4600 2975);
FORCEPROP 1 LAST PART_NUMBER A36096-155
J 0
(-4600 2825);
DISPLAY 0.638298 (-4600 2825);
PAINT BLUE (-4600 2825);
FORCEPROP 1 LAST PACK_TYPE 0402
J 0
(-4600 2775);
DISPLAY 0.638298 (-4600 2775);
PAINT SKYBLUE (-4600 2775);
FORCEPROP 2 LAST CDS_LIB mstr_discrete
J 0
(-4650 2975);
PAINT MONO (-4650 2975);
DISPLAY INVISIBLE (-4650 2975);
FORCEPROP 1 LAST PATH I485
J 0
(-4600 3125);
DISPLAY 0.978723 (-4600 3125);
PAINT WHITE (-4600 3125);
DISPLAY INVISIBLE (-4600 3125);
FORCEPROP 1 LASTPIN (-4650 2875) $PN 2
J 0
(-4640 2855);
DISPLAY 0.787234 (-4640 2855);
PAINT ORANGE (-4640 2855);
DISPLAY INVISIBLE (-4640 2855);
FORCEPROP 1 LASTPIN (-4650 3075) $PN 1
J 0
(-4640 3055);
DISPLAY 0.787234 (-4640 3055);
PAINT ORANGE (-4640 3055);
DISPLAY INVISIBLE (-4640 3055);
FORCEADD CAP..1
(-5650 2675);
FORCEPROP 0 LAST GROUP PCIE_RISER
J 0
(-5600 2425);
DISPLAY 0.638298 (-5600 2425);
PAINT BROWN (-5600 2425);
DISPLAY BOTH (-5600 2425);
FORCEPROP 1 LAST VALUE 0.22UF
J 0
(-5600 2725);
DISPLAY 0.638298 (-5600 2725);
PAINT SKYBLUE (-5600 2725);
FORCEPROP 1 LAST VOLTAGE 16V
J 0
(-5600 2675);
DISPLAY 0.638298 (-5600 2675);
PAINT SKYBLUE (-5600 2675);
FORCEPROP 1 LAST TOLERANCE 10%
J 0
(-5600 2625);
DISPLAY 0.638298 (-5600 2625);
PAINT SKYBLUE (-5600 2625);
FORCEPROP 1 LAST MATERIAL X7R
J 0
(-5600 2575);
DISPLAY 0.638298 (-5600 2575);
PAINT SKYBLUE (-5600 2575);
FORCEPROP 1 LAST PACK_TYPE 0402
J 0
(-5600 2475);
DISPLAY 0.638298 (-5600 2475);
PAINT SKYBLUE (-5600 2475);
FORCEPROP 1 LAST PART_NUMBER A36096-155
J 0
(-5600 2525);
DISPLAY 0.638298 (-5600 2525);
PAINT BLUE (-5600 2525);
FORCEPROP 1 LAST LOCATION C3P38
J 0
(-5600 2775);
DISPLAY 0.638298 (-5600 2775);
PAINT SKYBLUE (-5600 2775);
FORCEPROP 2 LAST CDS_LIB mstr_discrete
J 0
(-5650 2675);
PAINT MONO (-5650 2675);
DISPLAY INVISIBLE (-5650 2675);
FORCEPROP 1 LAST PATH I486
J 0
(-5600 2825);
DISPLAY 0.978723 (-5600 2825);
PAINT WHITE (-5600 2825);
DISPLAY INVISIBLE (-5600 2825);
FORCEPROP 1 LASTPIN (-5650 2575) $PN 2
J 0
(-5640 2555);
DISPLAY 0.787234 (-5640 2555);
PAINT ORANGE (-5640 2555);
DISPLAY INVISIBLE (-5640 2555);
FORCEPROP 1 LASTPIN (-5650 2775) $PN 1
J 0
(-5640 2755);
DISPLAY 0.787234 (-5640 2755);
PAINT ORANGE (-5640 2755);
DISPLAY INVISIBLE (-5640 2755);
FORCEADD CAP..1
(-5050 2975);
FORCEPROP 0 LAST GROUP PCIE_RISER
J 0
(-5000 3125);
DISPLAY 0.638298 (-5000 3125);
PAINT BROWN (-5000 3125);
DISPLAY BOTH (-5000 3125);
FORCEPROP 1 LAST MATERIAL X7R
J 0
(-5000 2875);
DISPLAY 0.638298 (-5000 2875);
PAINT SKYBLUE (-5000 2875);
FORCEPROP 1 LAST LOCATION C3P26
J 0
(-5000 3075);
DISPLAY 0.638298 (-5000 3075);
PAINT SKYBLUE (-5000 3075);
FORCEPROP 1 LAST PART_NUMBER A36096-155
J 0
(-5000 2825);
DISPLAY 0.638298 (-5000 2825);
PAINT BLUE (-5000 2825);
FORCEPROP 1 LAST PACK_TYPE 0402
J 0
(-5000 2775);
DISPLAY 0.638298 (-5000 2775);
PAINT SKYBLUE (-5000 2775);
FORCEPROP 1 LAST TOLERANCE 10%
J 0
(-5000 2925);
DISPLAY 0.638298 (-5000 2925);
PAINT SKYBLUE (-5000 2925);
FORCEPROP 1 LAST VOLTAGE 16V
J 0
(-5000 2975);
DISPLAY 0.638298 (-5000 2975);
PAINT SKYBLUE (-5000 2975);
FORCEPROP 1 LAST VALUE 0.22UF
J 0
(-5000 3025);
DISPLAY 0.638298 (-5000 3025);
PAINT SKYBLUE (-5000 3025);
FORCEPROP 2 LAST CDS_LIB mstr_discrete
J 0
(-5050 2975);
PAINT MONO (-5050 2975);
DISPLAY INVISIBLE (-5050 2975);
FORCEPROP 1 LAST PATH I487
J 0
(-5000 3125);
DISPLAY 0.978723 (-5000 3125);
PAINT WHITE (-5000 3125);
DISPLAY INVISIBLE (-5000 3125);
FORCEPROP 1 LASTPIN (-5050 2875) $PN 2
J 0
(-5040 2855);
DISPLAY 0.787234 (-5040 2855);
PAINT ORANGE (-5040 2855);
DISPLAY INVISIBLE (-5040 2855);
FORCEPROP 1 LASTPIN (-5050 3075) $PN 1
J 0
(-5040 3055);
DISPLAY 0.787234 (-5040 3055);
PAINT ORANGE (-5040 3055);
DISPLAY INVISIBLE (-5040 3055);
FORCEADD CAP..1
(-5250 2675);
FORCEPROP 0 LAST GROUP PCIE_RISER
J 0
(-5200 2425);
DISPLAY 0.638298 (-5200 2425);
PAINT BROWN (-5200 2425);
DISPLAY BOTH (-5200 2425);
FORCEPROP 1 LAST LOCATION C3P31
J 0
(-5200 2775);
DISPLAY 0.638298 (-5200 2775);
PAINT SKYBLUE (-5200 2775);
FORCEPROP 1 LAST VALUE 0.22UF
J 0
(-5200 2725);
DISPLAY 0.638298 (-5200 2725);
PAINT SKYBLUE (-5200 2725);
FORCEPROP 1 LAST VOLTAGE 16V
J 0
(-5200 2675);
DISPLAY 0.638298 (-5200 2675);
PAINT SKYBLUE (-5200 2675);
FORCEPROP 1 LAST TOLERANCE 10%
J 0
(-5200 2625);
DISPLAY 0.638298 (-5200 2625);
PAINT SKYBLUE (-5200 2625);
FORCEPROP 1 LAST MATERIAL X7R
J 0
(-5200 2575);
DISPLAY 0.638298 (-5200 2575);
PAINT SKYBLUE (-5200 2575);
FORCEPROP 1 LAST PART_NUMBER A36096-155
J 0
(-5200 2525);
DISPLAY 0.638298 (-5200 2525);
PAINT BLUE (-5200 2525);
FORCEPROP 1 LAST PACK_TYPE 0402
J 0
(-5200 2475);
DISPLAY 0.638298 (-5200 2475);
PAINT SKYBLUE (-5200 2475);
FORCEPROP 2 LAST CDS_LIB mstr_discrete
J 0
(-5250 2675);
PAINT MONO (-5250 2675);
DISPLAY INVISIBLE (-5250 2675);
FORCEPROP 1 LAST PATH I488
J 0
(-5200 2825);
DISPLAY 0.978723 (-5200 2825);
PAINT WHITE (-5200 2825);
DISPLAY INVISIBLE (-5200 2825);
FORCEPROP 1 LASTPIN (-5250 2575) $PN 2
J 0
(-5240 2555);
DISPLAY 0.787234 (-5240 2555);
PAINT ORANGE (-5240 2555);
DISPLAY INVISIBLE (-5240 2555);
FORCEPROP 1 LASTPIN (-5250 2775) $PN 1
J 0
(-5240 2755);
DISPLAY 0.787234 (-5240 2755);
PAINT ORANGE (-5240 2755);
DISPLAY INVISIBLE (-5240 2755);
FORCEADD CAP..1
(-5450 2975);
FORCEPROP 0 LAST GROUP PCIE_RISER
J 0
(-5400 3125);
DISPLAY 0.638298 (-5400 3125);
PAINT BROWN (-5400 3125);
DISPLAY BOTH (-5400 3125);
FORCEPROP 1 LAST PART_NUMBER A36096-155
J 0
(-5400 2825);
DISPLAY 0.638298 (-5400 2825);
PAINT BLUE (-5400 2825);
FORCEPROP 1 LAST PACK_TYPE 0402
J 0
(-5400 2775);
DISPLAY 0.638298 (-5400 2775);
PAINT SKYBLUE (-5400 2775);
FORCEPROP 1 LAST MATERIAL X7R
J 0
(-5400 2875);
DISPLAY 0.638298 (-5400 2875);
PAINT SKYBLUE (-5400 2875);
FORCEPROP 1 LAST TOLERANCE 10%
J 0
(-5400 2925);
DISPLAY 0.638298 (-5400 2925);
PAINT SKYBLUE (-5400 2925);
FORCEPROP 1 LAST VALUE 0.22UF
J 0
(-5400 3025);
DISPLAY 0.638298 (-5400 3025);
PAINT SKYBLUE (-5400 3025);
FORCEPROP 1 LAST LOCATION C3P34
J 0
(-5400 3075);
DISPLAY 0.638298 (-5400 3075);
PAINT SKYBLUE (-5400 3075);
FORCEPROP 1 LAST VOLTAGE 16V
J 0
(-5400 2975);
DISPLAY 0.638298 (-5400 2975);
PAINT SKYBLUE (-5400 2975);
FORCEPROP 2 LAST CDS_LIB mstr_discrete
J 0
(-5450 2975);
PAINT MONO (-5450 2975);
DISPLAY INVISIBLE (-5450 2975);
FORCEPROP 1 LAST PATH I489
J 0
(-5400 3125);
DISPLAY 0.978723 (-5400 3125);
PAINT WHITE (-5400 3125);
DISPLAY INVISIBLE (-5400 3125);
FORCEPROP 1 LASTPIN (-5450 2875) $PN 2
J 0
(-5440 2855);
DISPLAY 0.787234 (-5440 2855);
PAINT ORANGE (-5440 2855);
DISPLAY INVISIBLE (-5440 2855);
FORCEPROP 1 LASTPIN (-5450 3075) $PN 1
J 0
(-5440 3055);
DISPLAY 0.787234 (-5440 3055);
PAINT ORANGE (-5440 3055);
DISPLAY INVISIBLE (-5440 3055);
FORCEADD RES..1
R 1
(-825 4125);
FORCEPROP 1 LAST VALUE 0.0
J 2
(-725 4225);
DISPLAY 0.638298 (-725 4225);
PAINT SKYBLUE (-725 4225);
FORCEPROP 1 LAST PACK_TYPE 0402
J 0
(-775 3975);
DISPLAY 0.638298 (-775 3975);
PAINT SKYBLUE (-775 3975);
FORCEPROP 1 LAST WATTAGE 1/16W
J 2
(-650 4125);
DISPLAY 0.638298 (-650 4125);
PAINT SKYBLUE (-650 4125);
FORCEPROP 1 LAST TOLERANCE 5%
J 0
(-775 4175);
DISPLAY 0.638298 (-775 4175);
PAINT SKYBLUE (-775 4175);
FORCEPROP 1 LAST PART_NUMBER G21497-005
J 0
(-775 4025);
DISPLAY 0.638298 (-775 4025);
PAINT BLUE (-775 4025);
FORCEPROP 1 LAST MATERIAL CHIP
J 0
(-775 4075);
DISPLAY 0.638298 (-775 4075);
PAINT SKYBLUE (-775 4075);
FORCEPROP 1 LAST LOCATION R2U15
J 0
(-775 4275);
DISPLAY 0.638298 (-775 4275);
PAINT SKYBLUE (-775 4275);
FORCEPROP 0 LAST GROUP PCIE_RISER
J 0
(-775 3950);
DISPLAY 0.638298 (-775 3950);
PAINT BROWN (-775 3950);
DISPLAY BOTH (-775 3950);
FORCEPROP 2 LAST CDS_LIB mstr_discrete
R 1
J 0
(-825 4125);
PAINT MONO (-825 4125);
DISPLAY INVISIBLE (-825 4125);
FORCEPROP 1 LAST PATH I490
R 1
J 0
(-975 4075);
DISPLAY 0.978723 (-975 4075);
PAINT WHITE (-975 4075);
DISPLAY INVISIBLE (-975 4075);
FORCEPROP 1 LASTPIN (-825 4025) $PN 1
R 1
J 0
(-837 4037);
DISPLAY 0.787234 (-837 4037);
PAINT ORANGE (-837 4037);
DISPLAY INVISIBLE (-837 4037);
FORCEPROP 1 LASTPIN (-825 4225) $PN 2
R 1
J 0
(-837 4187);
DISPLAY 0.787234 (-837 4187);
PAINT ORANGE (-837 4187);
DISPLAY INVISIBLE (-837 4187);
FORCEADD RES..1
R 1
(-1425 3825);
FORCEPROP 1 LAST TOLERANCE 5%
J 0
(-1375 3875);
DISPLAY 0.638298 (-1375 3875);
PAINT SKYBLUE (-1375 3875);
FORCEPROP 1 LAST WATTAGE 1/16W
J 2
(-1250 3825);
DISPLAY 0.638298 (-1250 3825);
PAINT SKYBLUE (-1250 3825);
FORCEPROP 1 LAST PACK_TYPE 0402
J 0
(-1375 3675);
DISPLAY 0.638298 (-1375 3675);
PAINT SKYBLUE (-1375 3675);
FORCEPROP 1 LAST PART_NUMBER G21497-005
J 0
(-1375 3725);
DISPLAY 0.638298 (-1375 3725);
PAINT BLUE (-1375 3725);
FORCEPROP 1 LAST VALUE 0.0
J 2
(-1325 3925);
DISPLAY 0.638298 (-1325 3925);
PAINT SKYBLUE (-1325 3925);
FORCEPROP 1 LAST MATERIAL CHIP
J 0
(-1375 3775);
DISPLAY 0.638298 (-1375 3775);
PAINT SKYBLUE (-1375 3775);
FORCEPROP 1 LAST LOCATION R2U21
J 0
(-1375 3975);
DISPLAY 0.638298 (-1375 3975);
PAINT SKYBLUE (-1375 3975);
FORCEPROP 0 LAST GROUP PCIE_RISER
J 0
(-1400 3625);
DISPLAY 0.638298 (-1400 3625);
PAINT BROWN (-1400 3625);
DISPLAY BOTH (-1400 3625);
FORCEPROP 2 LAST CDS_LIB mstr_discrete
R 1
J 0
(-1425 3825);
PAINT MONO (-1425 3825);
DISPLAY INVISIBLE (-1425 3825);
FORCEPROP 1 LAST PATH I491
R 1
J 0
(-1575 3775);
DISPLAY 0.978723 (-1575 3775);
PAINT WHITE (-1575 3775);
DISPLAY INVISIBLE (-1575 3775);
FORCEPROP 1 LASTPIN (-1425 3725) $PN 1
R 1
J 0
(-1437 3737);
DISPLAY 0.787234 (-1437 3737);
PAINT ORANGE (-1437 3737);
DISPLAY INVISIBLE (-1437 3737);
FORCEPROP 1 LASTPIN (-1425 3925) $PN 2
R 1
J 0
(-1437 3887);
DISPLAY 0.787234 (-1437 3887);
PAINT ORANGE (-1437 3887);
DISPLAY INVISIBLE (-1437 3887);
FORCEADD RES..1
R 1
(-1025 3825);
FORCEPROP 0 LAST GROUP PCIE_RISER
J 0
(-1000 3625);
DISPLAY 0.638298 (-1000 3625);
PAINT BROWN (-1000 3625);
DISPLAY BOTH (-1000 3625);
FORCEPROP 1 LAST PART_NUMBER G21497-005
J 0
(-975 3725);
DISPLAY 0.638298 (-975 3725);
PAINT BLUE (-975 3725);
FORCEPROP 1 LAST PACK_TYPE 0402
J 0
(-975 3675);
DISPLAY 0.638298 (-975 3675);
PAINT SKYBLUE (-975 3675);
FORCEPROP 1 LAST WATTAGE 1/16W
J 2
(-850 3825);
DISPLAY 0.638298 (-850 3825);
PAINT SKYBLUE (-850 3825);
FORCEPROP 1 LAST TOLERANCE 5%
J 0
(-975 3875);
DISPLAY 0.638298 (-975 3875);
PAINT SKYBLUE (-975 3875);
FORCEPROP 1 LAST LOCATION R2U17
J 0
(-975 3975);
DISPLAY 0.638298 (-975 3975);
PAINT SKYBLUE (-975 3975);
FORCEPROP 1 LAST MATERIAL CHIP
J 0
(-975 3775);
DISPLAY 0.638298 (-975 3775);
PAINT SKYBLUE (-975 3775);
FORCEPROP 1 LAST VALUE 0.0
J 2
(-925 3925);
DISPLAY 0.638298 (-925 3925);
PAINT SKYBLUE (-925 3925);
FORCEPROP 1 LAST PATH I492
R 1
J 0
(-1175 3775);
DISPLAY 0.978723 (-1175 3775);
PAINT WHITE (-1175 3775);
DISPLAY INVISIBLE (-1175 3775);
FORCEPROP 2 LAST CDS_LIB mstr_discrete
R 1
J 0
(-1025 3825);
PAINT MONO (-1025 3825);
DISPLAY INVISIBLE (-1025 3825);
FORCEPROP 1 LASTPIN (-1025 3725) $PN 1
R 1
J 0
(-1037 3737);
DISPLAY 0.787234 (-1037 3737);
PAINT ORANGE (-1037 3737);
DISPLAY INVISIBLE (-1037 3737);
FORCEPROP 1 LASTPIN (-1025 3925) $PN 2
R 1
J 0
(-1037 3887);
DISPLAY 0.787234 (-1037 3887);
PAINT ORANGE (-1037 3887);
DISPLAY INVISIBLE (-1037 3887);
FORCEADD RES..1
R 1
(-1225 4125);
FORCEPROP 1 LAST LOCATION R2U19
J 0
(-1175 4275);
DISPLAY 0.638298 (-1175 4275);
PAINT SKYBLUE (-1175 4275);
FORCEPROP 1 LAST PART_NUMBER G21497-005
J 0
(-1175 4025);
DISPLAY 0.638298 (-1175 4025);
PAINT BLUE (-1175 4025);
FORCEPROP 1 LAST VALUE 0.0
J 2
(-1125 4225);
DISPLAY 0.638298 (-1125 4225);
PAINT SKYBLUE (-1125 4225);
FORCEPROP 1 LAST PACK_TYPE 0402
J 0
(-1175 3975);
DISPLAY 0.638298 (-1175 3975);
PAINT SKYBLUE (-1175 3975);
FORCEPROP 1 LAST MATERIAL CHIP
J 0
(-1175 4075);
DISPLAY 0.638298 (-1175 4075);
PAINT SKYBLUE (-1175 4075);
FORCEPROP 1 LAST WATTAGE 1/16W
J 2
(-1050 4125);
DISPLAY 0.638298 (-1050 4125);
PAINT SKYBLUE (-1050 4125);
FORCEPROP 1 LAST TOLERANCE 5%
J 0
(-1175 4175);
DISPLAY 0.638298 (-1175 4175);
PAINT SKYBLUE (-1175 4175);
FORCEPROP 0 LAST GROUP PCIE_RISER
J 0
(-1200 3950);
DISPLAY 0.638298 (-1200 3950);
PAINT BROWN (-1200 3950);
DISPLAY BOTH (-1200 3950);
FORCEPROP 1 LAST PATH I493
R 1
J 0
(-1375 4075);
DISPLAY 0.978723 (-1375 4075);
PAINT WHITE (-1375 4075);
DISPLAY INVISIBLE (-1375 4075);
FORCEPROP 2 LAST CDS_LIB mstr_discrete
R 1
J 0
(-1225 4125);
PAINT MONO (-1225 4125);
DISPLAY INVISIBLE (-1225 4125);
FORCEPROP 1 LASTPIN (-1225 4025) $PN 1
R 1
J 0
(-1237 4037);
DISPLAY 0.787234 (-1237 4037);
PAINT ORANGE (-1237 4037);
DISPLAY INVISIBLE (-1237 4037);
FORCEPROP 1 LASTPIN (-1225 4225) $PN 2
R 1
J 0
(-1237 4187);
DISPLAY 0.787234 (-1237 4187);
PAINT ORANGE (-1237 4187);
DISPLAY INVISIBLE (-1237 4187);
FORCEADD RES..1
R 1
(-2225 3825);
FORCEPROP 0 LAST GROUP PCIE_RISER
J 0
(-2225 3625);
DISPLAY 0.638298 (-2225 3625);
PAINT BROWN (-2225 3625);
DISPLAY BOTH (-2225 3625);
FORCEPROP 1 LAST WATTAGE 1/16W
J 2
(-2050 3825);
DISPLAY 0.638298 (-2050 3825);
PAINT SKYBLUE (-2050 3825);
FORCEPROP 1 LAST TOLERANCE 5%
J 0
(-2175 3875);
DISPLAY 0.638298 (-2175 3875);
PAINT SKYBLUE (-2175 3875);
FORCEPROP 1 LAST MATERIAL CHIP
J 0
(-2175 3775);
DISPLAY 0.638298 (-2175 3775);
PAINT SKYBLUE (-2175 3775);
FORCEPROP 1 LAST PACK_TYPE 0402
J 0
(-2175 3675);
DISPLAY 0.638298 (-2175 3675);
PAINT SKYBLUE (-2175 3675);
FORCEPROP 1 LAST VALUE 0.0
J 2
(-2125 3925);
DISPLAY 0.638298 (-2125 3925);
PAINT SKYBLUE (-2125 3925);
FORCEPROP 1 LAST PART_NUMBER G21497-005
J 0
(-2175 3725);
DISPLAY 0.638298 (-2175 3725);
PAINT BLUE (-2175 3725);
FORCEPROP 1 LAST LOCATION R2U29
J 0
(-2175 3975);
DISPLAY 0.638298 (-2175 3975);
PAINT SKYBLUE (-2175 3975);
FORCEPROP 1 LAST PATH I494
R 1
J 0
(-2375 3775);
DISPLAY 0.978723 (-2375 3775);
PAINT WHITE (-2375 3775);
DISPLAY INVISIBLE (-2375 3775);
FORCEPROP 2 LAST CDS_LIB mstr_discrete
R 1
J 0
(-2225 3825);
PAINT MONO (-2225 3825);
DISPLAY INVISIBLE (-2225 3825);
FORCEPROP 1 LASTPIN (-2225 3725) $PN 1
R 1
J 0
(-2237 3737);
DISPLAY 0.787234 (-2237 3737);
PAINT ORANGE (-2237 3737);
DISPLAY INVISIBLE (-2237 3737);
FORCEPROP 1 LASTPIN (-2225 3925) $PN 2
R 1
J 0
(-2237 3887);
DISPLAY 0.787234 (-2237 3887);
PAINT ORANGE (-2237 3887);
DISPLAY INVISIBLE (-2237 3887);
FORCEADD RES..1
R 1
(-1625 4125);
FORCEPROP 1 LAST TOLERANCE 5%
J 0
(-1575 4175);
DISPLAY 0.638298 (-1575 4175);
PAINT SKYBLUE (-1575 4175);
FORCEPROP 1 LAST WATTAGE 1/16W
J 2
(-1450 4125);
DISPLAY 0.638298 (-1450 4125);
PAINT SKYBLUE (-1450 4125);
FORCEPROP 1 LAST MATERIAL CHIP
J 0
(-1575 4075);
DISPLAY 0.638298 (-1575 4075);
PAINT SKYBLUE (-1575 4075);
FORCEPROP 1 LAST PART_NUMBER G21497-005
J 0
(-1575 4025);
DISPLAY 0.638298 (-1575 4025);
PAINT BLUE (-1575 4025);
FORCEPROP 1 LAST LOCATION R2U23
J 0
(-1575 4275);
DISPLAY 0.638298 (-1575 4275);
PAINT SKYBLUE (-1575 4275);
FORCEPROP 1 LAST VALUE 0.0
J 2
(-1525 4225);
DISPLAY 0.638298 (-1525 4225);
PAINT SKYBLUE (-1525 4225);
FORCEPROP 1 LAST PACK_TYPE 0402
J 0
(-1575 3975);
DISPLAY 0.638298 (-1575 3975);
PAINT SKYBLUE (-1575 3975);
FORCEPROP 0 LAST GROUP PCIE_RISER
J 0
(-1600 3950);
DISPLAY 0.638298 (-1600 3950);
PAINT BROWN (-1600 3950);
DISPLAY BOTH (-1600 3950);
FORCEPROP 1 LAST PATH I495
R 1
J 0
(-1775 4075);
DISPLAY 0.978723 (-1775 4075);
PAINT WHITE (-1775 4075);
DISPLAY INVISIBLE (-1775 4075);
FORCEPROP 2 LAST CDS_LIB mstr_discrete
R 1
J 0
(-1625 4125);
PAINT MONO (-1625 4125);
DISPLAY INVISIBLE (-1625 4125);
FORCEPROP 1 LASTPIN (-1625 4025) $PN 1
R 1
J 0
(-1637 4037);
DISPLAY 0.787234 (-1637 4037);
PAINT ORANGE (-1637 4037);
DISPLAY INVISIBLE (-1637 4037);
FORCEPROP 1 LASTPIN (-1625 4225) $PN 2
R 1
J 0
(-1637 4187);
DISPLAY 0.787234 (-1637 4187);
PAINT ORANGE (-1637 4187);
DISPLAY INVISIBLE (-1637 4187);
FORCEADD RES..1
R 1
(-1825 3825);
FORCEPROP 1 LAST TOLERANCE 5%
J 0
(-1775 3875);
DISPLAY 0.638298 (-1775 3875);
PAINT SKYBLUE (-1775 3875);
FORCEPROP 1 LAST WATTAGE 1/16W
J 2
(-1650 3825);
DISPLAY 0.638298 (-1650 3825);
PAINT SKYBLUE (-1650 3825);
FORCEPROP 1 LAST MATERIAL CHIP
J 0
(-1775 3775);
DISPLAY 0.638298 (-1775 3775);
PAINT SKYBLUE (-1775 3775);
FORCEPROP 1 LAST PART_NUMBER G21497-005
J 0
(-1775 3725);
DISPLAY 0.638298 (-1775 3725);
PAINT BLUE (-1775 3725);
FORCEPROP 1 LAST PACK_TYPE 0402
J 0
(-1775 3675);
DISPLAY 0.638298 (-1775 3675);
PAINT SKYBLUE (-1775 3675);
FORCEPROP 1 LAST VALUE 0.0
J 2
(-1725 3925);
DISPLAY 0.638298 (-1725 3925);
PAINT SKYBLUE (-1725 3925);
FORCEPROP 1 LAST LOCATION R2U25
J 0
(-1775 3975);
DISPLAY 0.638298 (-1775 3975);
PAINT SKYBLUE (-1775 3975);
FORCEPROP 0 LAST GROUP PCIE_RISER
J 0
(-1800 3625);
DISPLAY 0.638298 (-1800 3625);
PAINT BROWN (-1800 3625);
DISPLAY BOTH (-1800 3625);
FORCEPROP 1 LAST PATH I496
R 1
J 0
(-1975 3775);
DISPLAY 0.978723 (-1975 3775);
PAINT WHITE (-1975 3775);
DISPLAY INVISIBLE (-1975 3775);
FORCEPROP 2 LAST CDS_LIB mstr_discrete
R 1
J 0
(-1825 3825);
PAINT MONO (-1825 3825);
DISPLAY INVISIBLE (-1825 3825);
FORCEPROP 1 LASTPIN (-1825 3725) $PN 1
R 1
J 0
(-1837 3737);
DISPLAY 0.787234 (-1837 3737);
PAINT ORANGE (-1837 3737);
DISPLAY INVISIBLE (-1837 3737);
FORCEPROP 1 LASTPIN (-1825 3925) $PN 2
R 1
J 0
(-1837 3887);
DISPLAY 0.787234 (-1837 3887);
PAINT ORANGE (-1837 3887);
DISPLAY INVISIBLE (-1837 3887);
FORCEADD RES..1
R 1
(-2025 4125);
FORCEPROP 0 LAST GROUP PCIE_RISER
J 0
(-2000 3950);
DISPLAY 0.638298 (-2000 3950);
PAINT BROWN (-2000 3950);
DISPLAY BOTH (-2000 3950);
FORCEPROP 1 LAST VALUE 0.0
J 2
(-1925 4225);
DISPLAY 0.638298 (-1925 4225);
PAINT SKYBLUE (-1925 4225);
FORCEPROP 1 LAST PACK_TYPE 0402
J 0
(-1975 3975);
DISPLAY 0.638298 (-1975 3975);
PAINT SKYBLUE (-1975 3975);
FORCEPROP 1 LAST MATERIAL CHIP
J 0
(-1975 4075);
DISPLAY 0.638298 (-1975 4075);
PAINT SKYBLUE (-1975 4075);
FORCEPROP 1 LAST WATTAGE 1/16W
J 2
(-1850 4125);
DISPLAY 0.638298 (-1850 4125);
PAINT SKYBLUE (-1850 4125);
FORCEPROP 1 LAST TOLERANCE 5%
J 0
(-1975 4175);
DISPLAY 0.638298 (-1975 4175);
PAINT SKYBLUE (-1975 4175);
FORCEPROP 1 LAST LOCATION R2U27
J 0
(-1975 4275);
DISPLAY 0.638298 (-1975 4275);
PAINT SKYBLUE (-1975 4275);
FORCEPROP 1 LAST PART_NUMBER G21497-005
J 0
(-1975 4025);
DISPLAY 0.638298 (-1975 4025);
PAINT BLUE (-1975 4025);
FORCEPROP 1 LAST PATH I497
R 1
J 0
(-2175 4075);
DISPLAY 0.978723 (-2175 4075);
PAINT WHITE (-2175 4075);
DISPLAY INVISIBLE (-2175 4075);
FORCEPROP 2 LAST CDS_LIB mstr_discrete
R 1
J 0
(-2025 4125);
PAINT MONO (-2025 4125);
DISPLAY INVISIBLE (-2025 4125);
FORCEPROP 1 LASTPIN (-2025 4025) $PN 1
R 1
J 0
(-2037 4037);
DISPLAY 0.787234 (-2037 4037);
PAINT ORANGE (-2037 4037);
DISPLAY INVISIBLE (-2037 4037);
FORCEPROP 1 LASTPIN (-2025 4225) $PN 2
R 1
J 0
(-2037 4187);
DISPLAY 0.787234 (-2037 4187);
PAINT ORANGE (-2037 4187);
DISPLAY INVISIBLE (-2037 4187);
FORCEADD RES..1
R 1
(-2000 3100);
FORCEPROP 0 LAST GROUP PCIE_RISER
J 0
(-1950 2925);
DISPLAY 0.638298 (-1950 2925);
PAINT BROWN (-1950 2925);
DISPLAY BOTH (-1950 2925);
FORCEPROP 1 LAST TOLERANCE 5%
J 0
(-1950 3150);
DISPLAY 0.638298 (-1950 3150);
PAINT SKYBLUE (-1950 3150);
FORCEPROP 1 LAST LOCATION R2U26
J 0
(-1950 3250);
DISPLAY 0.638298 (-1950 3250);
PAINT SKYBLUE (-1950 3250);
FORCEPROP 1 LAST WATTAGE 1/16W
J 2
(-1825 3100);
DISPLAY 0.638298 (-1825 3100);
PAINT SKYBLUE (-1825 3100);
FORCEPROP 1 LAST PACK_TYPE 0402
J 0
(-1950 2950);
DISPLAY 0.638298 (-1950 2950);
PAINT SKYBLUE (-1950 2950);
FORCEPROP 1 LAST MATERIAL CHIP
J 0
(-1950 3050);
DISPLAY 0.638298 (-1950 3050);
PAINT SKYBLUE (-1950 3050);
FORCEPROP 1 LAST VALUE 0.0
J 2
(-1900 3200);
DISPLAY 0.638298 (-1900 3200);
PAINT SKYBLUE (-1900 3200);
FORCEPROP 1 LAST PART_NUMBER G21497-005
J 0
(-1950 3000);
DISPLAY 0.638298 (-1950 3000);
PAINT BLUE (-1950 3000);
FORCEPROP 1 LAST PATH I498
R 1
J 0
(-2150 3050);
DISPLAY 0.978723 (-2150 3050);
PAINT WHITE (-2150 3050);
DISPLAY INVISIBLE (-2150 3050);
FORCEPROP 2 LAST CDS_LIB mstr_discrete
R 1
J 0
(-2000 3100);
PAINT MONO (-2000 3100);
DISPLAY INVISIBLE (-2000 3100);
FORCEPROP 1 LASTPIN (-2000 3000) $PN 1
R 1
J 0
(-2012 3012);
DISPLAY 0.787234 (-2012 3012);
PAINT ORANGE (-2012 3012);
DISPLAY INVISIBLE (-2012 3012);
FORCEPROP 1 LASTPIN (-2000 3200) $PN 2
R 1
J 0
(-2012 3162);
DISPLAY 0.787234 (-2012 3162);
PAINT ORANGE (-2012 3162);
DISPLAY INVISIBLE (-2012 3162);
FORCEADD RES..1
R 1
(-800 3100);
FORCEPROP 0 LAST GROUP PCIE_RISER
J 0
(-750 2900);
DISPLAY 0.638298 (-750 2900);
PAINT BROWN (-750 2900);
DISPLAY BOTH (-750 2900);
FORCEPROP 1 LAST LOCATION R2U14
J 0
(-750 3250);
DISPLAY 0.638298 (-750 3250);
PAINT SKYBLUE (-750 3250);
FORCEPROP 1 LAST VALUE 0.0
J 2
(-700 3200);
DISPLAY 0.638298 (-700 3200);
PAINT SKYBLUE (-700 3200);
FORCEPROP 1 LAST TOLERANCE 5%
J 0
(-750 3150);
DISPLAY 0.638298 (-750 3150);
PAINT SKYBLUE (-750 3150);
FORCEPROP 1 LAST WATTAGE 1/16W
J 2
(-625 3100);
DISPLAY 0.638298 (-625 3100);
PAINT SKYBLUE (-625 3100);
FORCEPROP 1 LAST PART_NUMBER G21497-005
J 0
(-750 3000);
DISPLAY 0.638298 (-750 3000);
PAINT BLUE (-750 3000);
FORCEPROP 1 LAST PACK_TYPE 0402
J 0
(-750 2950);
DISPLAY 0.638298 (-750 2950);
PAINT SKYBLUE (-750 2950);
FORCEPROP 1 LAST MATERIAL CHIP
J 0
(-750 3050);
DISPLAY 0.638298 (-750 3050);
PAINT SKYBLUE (-750 3050);
FORCEPROP 1 LAST PATH I499
R 1
J 0
(-950 3050);
DISPLAY 0.978723 (-950 3050);
PAINT WHITE (-950 3050);
DISPLAY INVISIBLE (-950 3050);
FORCEPROP 2 LAST CDS_LIB mstr_discrete
R 1
J 0
(-800 3100);
PAINT MONO (-800 3100);
DISPLAY INVISIBLE (-800 3100);
FORCEPROP 1 LASTPIN (-800 3000) $PN 1
R 1
J 0
(-812 3012);
DISPLAY 0.787234 (-812 3012);
PAINT ORANGE (-812 3012);
DISPLAY INVISIBLE (-812 3012);
FORCEPROP 1 LASTPIN (-800 3200) $PN 2
R 1
J 0
(-812 3162);
DISPLAY 0.787234 (-812 3162);
PAINT ORANGE (-812 3162);
DISPLAY INVISIBLE (-812 3162);
FORCEADD RES..1
R 1
(-2200 2800);
FORCEPROP 0 LAST GROUP PCIE_RISER
J 0
(-2175 2600);
DISPLAY 0.638298 (-2175 2600);
PAINT BROWN (-2175 2600);
DISPLAY BOTH (-2175 2600);
FORCEPROP 1 LAST PART_NUMBER G21497-005
J 0
(-2150 2700);
DISPLAY 0.638298 (-2150 2700);
PAINT BLUE (-2150 2700);
FORCEPROP 1 LAST PACK_TYPE 0402
J 0
(-2150 2650);
DISPLAY 0.638298 (-2150 2650);
PAINT SKYBLUE (-2150 2650);
FORCEPROP 1 LAST MATERIAL CHIP
J 0
(-2150 2750);
DISPLAY 0.638298 (-2150 2750);
PAINT SKYBLUE (-2150 2750);
FORCEPROP 1 LAST LOCATION R2U28
J 0
(-2150 2950);
DISPLAY 0.638298 (-2150 2950);
PAINT SKYBLUE (-2150 2950);
FORCEPROP 1 LAST WATTAGE 1/16W
J 2
(-2025 2800);
DISPLAY 0.638298 (-2025 2800);
PAINT SKYBLUE (-2025 2800);
FORCEPROP 1 LAST TOLERANCE 5%
J 0
(-2150 2850);
DISPLAY 0.638298 (-2150 2850);
PAINT SKYBLUE (-2150 2850);
FORCEPROP 1 LAST VALUE 0.0
J 2
(-2075 2900);
DISPLAY 0.638298 (-2075 2900);
PAINT SKYBLUE (-2075 2900);
FORCEPROP 1 LAST PATH I500
R 1
J 0
(-2350 2750);
DISPLAY 0.978723 (-2350 2750);
PAINT WHITE (-2350 2750);
DISPLAY INVISIBLE (-2350 2750);
FORCEPROP 2 LAST CDS_LIB mstr_discrete
R 1
J 0
(-2200 2800);
PAINT MONO (-2200 2800);
DISPLAY INVISIBLE (-2200 2800);
FORCEPROP 1 LASTPIN (-2200 2700) $PN 1
R 1
J 0
(-2212 2712);
DISPLAY 0.787234 (-2212 2712);
PAINT ORANGE (-2212 2712);
DISPLAY INVISIBLE (-2212 2712);
FORCEPROP 1 LASTPIN (-2200 2900) $PN 2
R 1
J 0
(-2212 2862);
DISPLAY 0.787234 (-2212 2862);
PAINT ORANGE (-2212 2862);
DISPLAY INVISIBLE (-2212 2862);
FORCEADD RES..1
R 1
(-1000 2800);
FORCEPROP 0 LAST GROUP PCIE_RISER
J 0
(-950 2600);
DISPLAY 0.638298 (-950 2600);
PAINT BROWN (-950 2600);
DISPLAY BOTH (-950 2600);
FORCEPROP 1 LAST LOCATION R2U16
J 0
(-950 2950);
DISPLAY 0.638298 (-950 2950);
PAINT SKYBLUE (-950 2950);
FORCEPROP 1 LAST VALUE 0.0
J 2
(-850 2900);
DISPLAY 0.638298 (-850 2900);
PAINT SKYBLUE (-850 2900);
FORCEPROP 1 LAST TOLERANCE 5%
J 0
(-950 2850);
DISPLAY 0.638298 (-950 2850);
PAINT SKYBLUE (-950 2850);
FORCEPROP 1 LAST WATTAGE 1/16W
J 2
(-825 2800);
DISPLAY 0.638298 (-825 2800);
PAINT SKYBLUE (-825 2800);
FORCEPROP 1 LAST MATERIAL CHIP
J 0
(-950 2750);
DISPLAY 0.638298 (-950 2750);
PAINT SKYBLUE (-950 2750);
FORCEPROP 1 LAST PACK_TYPE 0402
J 0
(-950 2650);
DISPLAY 0.638298 (-950 2650);
PAINT SKYBLUE (-950 2650);
FORCEPROP 1 LAST PART_NUMBER G21497-005
J 0
(-950 2700);
DISPLAY 0.638298 (-950 2700);
PAINT BLUE (-950 2700);
FORCEPROP 1 LAST PATH I501
R 1
J 0
(-1150 2750);
DISPLAY 0.978723 (-1150 2750);
PAINT WHITE (-1150 2750);
DISPLAY INVISIBLE (-1150 2750);
FORCEPROP 2 LAST CDS_LIB mstr_discrete
R 1
J 0
(-1000 2800);
PAINT MONO (-1000 2800);
DISPLAY INVISIBLE (-1000 2800);
FORCEPROP 1 LASTPIN (-1000 2700) $PN 1
R 1
J 0
(-1012 2712);
DISPLAY 0.787234 (-1012 2712);
PAINT ORANGE (-1012 2712);
DISPLAY INVISIBLE (-1012 2712);
FORCEPROP 1 LASTPIN (-1000 2900) $PN 2
R 1
J 0
(-1012 2862);
DISPLAY 0.787234 (-1012 2862);
PAINT ORANGE (-1012 2862);
DISPLAY INVISIBLE (-1012 2862);
FORCEADD RES..1
R 1
(-1200 3100);
FORCEPROP 0 LAST GROUP PCIE_RISER
J 0
(-1150 2925);
DISPLAY 0.638298 (-1150 2925);
PAINT BROWN (-1150 2925);
DISPLAY BOTH (-1150 2925);
FORCEPROP 1 LAST PART_NUMBER G21497-005
J 0
(-1150 3000);
DISPLAY 0.638298 (-1150 3000);
PAINT BLUE (-1150 3000);
FORCEPROP 1 LAST LOCATION R2U18
J 0
(-1150 3250);
DISPLAY 0.638298 (-1150 3250);
PAINT SKYBLUE (-1150 3250);
FORCEPROP 1 LAST TOLERANCE 5%
J 0
(-1150 3150);
DISPLAY 0.638298 (-1150 3150);
PAINT SKYBLUE (-1150 3150);
FORCEPROP 1 LAST WATTAGE 1/16W
J 2
(-1025 3100);
DISPLAY 0.638298 (-1025 3100);
PAINT SKYBLUE (-1025 3100);
FORCEPROP 1 LAST MATERIAL CHIP
J 0
(-1150 3050);
DISPLAY 0.638298 (-1150 3050);
PAINT SKYBLUE (-1150 3050);
FORCEPROP 1 LAST VALUE 0.0
J 2
(-1100 3200);
DISPLAY 0.638298 (-1100 3200);
PAINT SKYBLUE (-1100 3200);
FORCEPROP 1 LAST PACK_TYPE 0402
J 0
(-1150 2950);
DISPLAY 0.638298 (-1150 2950);
PAINT SKYBLUE (-1150 2950);
FORCEPROP 1 LAST PATH I502
R 1
J 0
(-1350 3050);
DISPLAY 0.978723 (-1350 3050);
PAINT WHITE (-1350 3050);
DISPLAY INVISIBLE (-1350 3050);
FORCEPROP 2 LAST CDS_LIB mstr_discrete
R 1
J 0
(-1200 3100);
PAINT MONO (-1200 3100);
DISPLAY INVISIBLE (-1200 3100);
FORCEPROP 1 LASTPIN (-1200 3000) $PN 1
R 1
J 0
(-1212 3012);
DISPLAY 0.787234 (-1212 3012);
PAINT ORANGE (-1212 3012);
DISPLAY INVISIBLE (-1212 3012);
FORCEPROP 1 LASTPIN (-1200 3200) $PN 2
R 1
J 0
(-1212 3162);
DISPLAY 0.787234 (-1212 3162);
PAINT ORANGE (-1212 3162);
DISPLAY INVISIBLE (-1212 3162);
FORCEADD RES..1
R 1
(-1400 2800);
FORCEPROP 0 LAST GROUP PCIE_RISER
J 0
(-1350 2600);
DISPLAY 0.638298 (-1350 2600);
PAINT BROWN (-1350 2600);
DISPLAY BOTH (-1350 2600);
FORCEPROP 1 LAST PART_NUMBER G21497-005
J 0
(-1350 2700);
DISPLAY 0.638298 (-1350 2700);
PAINT BLUE (-1350 2700);
FORCEPROP 1 LAST PACK_TYPE 0402
J 0
(-1350 2650);
DISPLAY 0.638298 (-1350 2650);
PAINT SKYBLUE (-1350 2650);
FORCEPROP 1 LAST MATERIAL CHIP
J 0
(-1350 2750);
DISPLAY 0.638298 (-1350 2750);
PAINT SKYBLUE (-1350 2750);
FORCEPROP 1 LAST WATTAGE 1/16W
J 2
(-1225 2800);
DISPLAY 0.638298 (-1225 2800);
PAINT SKYBLUE (-1225 2800);
FORCEPROP 1 LAST TOLERANCE 5%
J 0
(-1350 2850);
DISPLAY 0.638298 (-1350 2850);
PAINT SKYBLUE (-1350 2850);
FORCEPROP 1 LAST VALUE 0.0
J 2
(-1250 2900);
DISPLAY 0.638298 (-1250 2900);
PAINT SKYBLUE (-1250 2900);
FORCEPROP 1 LAST LOCATION R2U20
J 0
(-1350 2950);
DISPLAY 0.638298 (-1350 2950);
PAINT SKYBLUE (-1350 2950);
FORCEPROP 1 LAST PATH I503
R 1
J 0
(-1550 2750);
DISPLAY 0.978723 (-1550 2750);
PAINT WHITE (-1550 2750);
DISPLAY INVISIBLE (-1550 2750);
FORCEPROP 2 LAST CDS_LIB mstr_discrete
R 1
J 0
(-1400 2800);
PAINT MONO (-1400 2800);
DISPLAY INVISIBLE (-1400 2800);
FORCEPROP 1 LASTPIN (-1400 2700) $PN 1
R 1
J 0
(-1412 2712);
DISPLAY 0.787234 (-1412 2712);
PAINT ORANGE (-1412 2712);
DISPLAY INVISIBLE (-1412 2712);
FORCEPROP 1 LASTPIN (-1400 2900) $PN 2
R 1
J 0
(-1412 2862);
DISPLAY 0.787234 (-1412 2862);
PAINT ORANGE (-1412 2862);
DISPLAY INVISIBLE (-1412 2862);
FORCEADD RES..1
R 1
(-1600 3100);
FORCEPROP 0 LAST GROUP PCIE_RISER
J 0
(-1550 2925);
DISPLAY 0.638298 (-1550 2925);
PAINT BROWN (-1550 2925);
DISPLAY BOTH (-1550 2925);
FORCEPROP 1 LAST TOLERANCE 5%
J 0
(-1550 3150);
DISPLAY 0.638298 (-1550 3150);
PAINT SKYBLUE (-1550 3150);
FORCEPROP 1 LAST WATTAGE 1/16W
J 2
(-1425 3100);
DISPLAY 0.638298 (-1425 3100);
PAINT SKYBLUE (-1425 3100);
FORCEPROP 1 LAST VALUE 0.0
J 2
(-1500 3200);
DISPLAY 0.638298 (-1500 3200);
PAINT SKYBLUE (-1500 3200);
FORCEPROP 1 LAST MATERIAL CHIP
J 0
(-1550 3050);
DISPLAY 0.638298 (-1550 3050);
PAINT SKYBLUE (-1550 3050);
FORCEPROP 1 LAST LOCATION R2U22
J 0
(-1550 3250);
DISPLAY 0.638298 (-1550 3250);
PAINT SKYBLUE (-1550 3250);
FORCEPROP 1 LAST PACK_TYPE 0402
J 0
(-1550 2950);
DISPLAY 0.638298 (-1550 2950);
PAINT SKYBLUE (-1550 2950);
FORCEPROP 1 LAST PART_NUMBER G21497-005
J 0
(-1550 3000);
DISPLAY 0.638298 (-1550 3000);
PAINT BLUE (-1550 3000);
FORCEPROP 1 LAST PATH I504
R 1
J 0
(-1750 3050);
DISPLAY 0.978723 (-1750 3050);
PAINT WHITE (-1750 3050);
DISPLAY INVISIBLE (-1750 3050);
FORCEPROP 2 LAST CDS_LIB mstr_discrete
R 1
J 0
(-1600 3100);
PAINT MONO (-1600 3100);
DISPLAY INVISIBLE (-1600 3100);
FORCEPROP 1 LASTPIN (-1600 3000) $PN 1
R 1
J 0
(-1612 3012);
DISPLAY 0.787234 (-1612 3012);
PAINT ORANGE (-1612 3012);
DISPLAY INVISIBLE (-1612 3012);
FORCEPROP 1 LASTPIN (-1600 3200) $PN 2
R 1
J 0
(-1612 3162);
DISPLAY 0.787234 (-1612 3162);
PAINT ORANGE (-1612 3162);
DISPLAY INVISIBLE (-1612 3162);
FORCEADD RES..1
R 1
(-1800 2800);
FORCEPROP 0 LAST GROUP PCIE_RISER
J 0
(-1750 2600);
DISPLAY 0.638298 (-1750 2600);
PAINT BROWN (-1750 2600);
DISPLAY BOTH (-1750 2600);
FORCEPROP 1 LAST MATERIAL CHIP
J 0
(-1750 2750);
DISPLAY 0.638298 (-1750 2750);
PAINT SKYBLUE (-1750 2750);
FORCEPROP 1 LAST PACK_TYPE 0402
J 0
(-1750 2650);
DISPLAY 0.638298 (-1750 2650);
PAINT SKYBLUE (-1750 2650);
FORCEPROP 1 LAST TOLERANCE 5%
J 0
(-1750 2850);
DISPLAY 0.638298 (-1750 2850);
PAINT SKYBLUE (-1750 2850);
FORCEPROP 1 LAST WATTAGE 1/16W
J 2
(-1625 2800);
DISPLAY 0.638298 (-1625 2800);
PAINT SKYBLUE (-1625 2800);
FORCEPROP 1 LAST PART_NUMBER G21497-005
J 0
(-1750 2700);
DISPLAY 0.638298 (-1750 2700);
PAINT BLUE (-1750 2700);
FORCEPROP 1 LAST VALUE 0.0
J 2
(-1625 2900);
DISPLAY 0.638298 (-1625 2900);
PAINT SKYBLUE (-1625 2900);
FORCEPROP 1 LAST LOCATION R2U24
J 0
(-1750 2950);
DISPLAY 0.638298 (-1750 2950);
PAINT SKYBLUE (-1750 2950);
FORCEPROP 1 LAST PATH I505
R 1
J 0
(-1950 2750);
DISPLAY 0.978723 (-1950 2750);
PAINT WHITE (-1950 2750);
DISPLAY INVISIBLE (-1950 2750);
FORCEPROP 2 LAST CDS_LIB mstr_discrete
R 1
J 0
(-1800 2800);
PAINT MONO (-1800 2800);
DISPLAY INVISIBLE (-1800 2800);
FORCEPROP 1 LASTPIN (-1800 2700) $PN 1
R 1
J 0
(-1812 2712);
DISPLAY 0.787234 (-1812 2712);
PAINT ORANGE (-1812 2712);
DISPLAY INVISIBLE (-1812 2712);
FORCEPROP 1 LASTPIN (-1800 2900) $PN 2
R 1
J 0
(-1812 2862);
DISPLAY 0.787234 (-1812 2862);
PAINT ORANGE (-1812 2862);
DISPLAY INVISIBLE (-1812 2862);
FORCEADD BOM_NOTE..1
(-3350 2950);
FORCEPROP 0 LAST L1 STUFF FOR X24 SS SUPPORT
J 0
(-3450 2825);
DISPLAY 1.021277 (-3450 2825);
PAINT ORANGE (-3450 2825);
FORCEPROP 2 LAST CDS_LIB mstr_symbols
J 0
(-3350 2950);
PAINT ORANGE (-3350 2950);
DISPLAY INVISIBLE (-3350 2950);
FORCEPROP 1 LAST COMMENT_BODY TRUE
J 0
(-3325 3050);
DISPLAY 0.978723 (-3325 3050);
PAINT ORANGE (-3325 3050);
DISPLAY INVISIBLE (-3325 3050);
FORCEADD BOM_NOTE..1
(-4475 650);
FORCEPROP 0 LAST L1 UNSTUFF FOR X24 SS SUPPORT
J 0
(-4575 525);
DISPLAY 1.021277 (-4575 525);
PAINT ORANGE (-4575 525);
FORCEPROP 2 LAST CDS_LIB mstr_symbols
J 0
(-4475 650);
PAINT ORANGE (-4475 650);
DISPLAY INVISIBLE (-4475 650);
FORCEPROP 1 LAST COMMENT_BODY TRUE
J 0
(-4450 750);
DISPLAY 0.978723 (-4450 750);
PAINT ORANGE (-4450 750);
DISPLAY INVISIBLE (-4450 750);
FORCEADD INTEL_CORP_BPAGE..1
(125 -275);
FORCEPROP 1 LAST CDS_CON_LAST_MODIFIED Fri Jun 16 17:48:42 2017
J 0
(-1300 50);
DISPLAY 1.595745 (-1300 50);
PAINT GREEN (-1300 50);
DISPLAY INVISIBLE (-1300 50);
FORCEPROP 1 LAST CUSTOM_TXT_CDS <CURRENT_DESIGN_SHEET> OF <TOTAL_DESIGN_SHEETS>
J 0
(-375 -250);
PAINT ORANGE (-375 -250);
FORCEPROP 2 LAST CUSTOM_TXT_CDS <XR_PAGE_TITLE>
J 0
(-7765 4975);
DISPLAY 0.638298 (-7765 4975);
PAINT PINK (-7765 4975);
DISPLAY INVISIBLE (-7765 4975);
FORCEPROP 2 LAST CUSTOM_TXT_CDS <CON_LAST_MODIFIED>
J 0
(-3875 -175);
PAINT ORANGE (-3875 -175);
FORCEPROP 1 LAST SCH_TITLE PCIE STEERING
J 0
(-7825 -225);
DISPLAY 1.212766 (-7825 -225);
PAINT ORANGE (-7825 -225);
FORCEPROP 2 LAST PAGE_BORDER TRUE
J 0
(-7765 4975);
PAINT PINK (-7765 4975);
DISPLAY INVISIBLE (-7765 4975);
FORCEPROP 2 LAST CDS_LIB mstr_symbols
J 0
(125 -275);
DISPLAY 1.595745 (125 -275);
PAINT ORANGE (125 -275);
DISPLAY INVISIBLE (125 -275);
FORCEPROP 1 LAST COMMENT_BODY TRUE
J 0
(137 -263);
DISPLAY 0.744681 (137 -263);
PAINT GREEN (137 -263);
DISPLAY INVISIBLE (137 -263);
FORCEPROP 2 LAST CDS_XR_PAGE_TITLE CR-107 : @BASEBOARD_FAB2_LIB.BASEBOARD_FAB2(SCH_1):PAGE107
J 0
(-7765 4975);
DISPLAY 0.638298 (-7765 4975);
PAINT PINK (-7765 4975);
DISPLAY INVISIBLE (-7765 4975);
FORCEADD CAD_NOTE..1
(-3200 2675);
FORCEPROP 0 LAST L1 PLACE CLOSE TO X24 SLOT
J 0
(-3325 2550);
DISPLAY 1.021277 (-3325 2550);
PAINT ORANGE (-3325 2550);
FORCEPROP 2 LAST CDS_LIB mstr_symbols
J 0
(-3200 2675);
PAINT ORANGE (-3200 2675);
DISPLAY INVISIBLE (-3200 2675);
FORCEPROP 1 LAST COMMENT_BODY TRUE
J 0
(-3175 2775);
DISPLAY 0.978723 (-3175 2775);
PAINT ORANGE (-3175 2775);
DISPLAY INVISIBLE (-3175 2775);
FORCEADD CAD_NOTE..1
(-4200 350);
FORCEPROP 0 LAST L1 PLACE CLOSE TO PCH
J 0
(-4325 225);
DISPLAY 1.021277 (-4325 225);
PAINT ORANGE (-4325 225);
FORCEPROP 2 LAST CDS_LIB mstr_symbols
J 0
(-4200 350);
PAINT ORANGE (-4200 350);
DISPLAY INVISIBLE (-4200 350);
FORCEPROP 1 LAST COMMENT_BODY TRUE
J 0
(-4175 450);
DISPLAY 0.978723 (-4175 450);
PAINT ORANGE (-4175 450);
DISPLAY INVISIBLE (-4175 450);
WIRE 17 -1 (-3325 1225)(-3125 1225);
WIRE 17 -1 (-3125 1225)(-2925 1225);
WIRE 17 -1 (-2925 1225)(-2725 1225);
WIRE 17 -1 (-2725 1225)(-2525 1225);
FORCEPROP 2 LAST SIG_NAME P3E_CPU0_PE1_SS_RXN<7:0>
J 0
(-2535 1185);
DISPLAY 0.617021 (-2535 1185);
PAINT ORANGE (-2535 1185);
WIRE 17 -1 (-2525 1225)(-2325 1225);
WIRE 17 -1 (-1925 1225)(-1750 1225);
WIRE 17 -1 (-2325 1225)(-2125 1225);
WIRE 17 -1 (-2125 1225)(-1925 1225);
WIRE 17 -1 (-7000 1175)(-6900 1175);
FORCEPROP 2 LAST SIG_NAME P3E_CPU0_PE1_SS_TXP<7:0>
J 0
(-6960 1185);
DISPLAY 0.617021 (-6960 1185);
PAINT ORANGE (-6960 1185);
WIRE 17 -1 (-6900 1175)(-6700 1175);
WIRE 17 -1 (-6700 1175)(-6500 1175);
WIRE 17 -1 (-6500 1175)(-6300 1175);
WIRE 17 -1 (-5700 1175)(-5500 1175);
WIRE 17 -1 (-5900 1175)(-5700 1175);
WIRE 17 -1 (-6300 1175)(-6100 1175);
WIRE 17 -1 (-6100 1175)(-5900 1175);
WIRE 17 -1 (-5500 1275)(-5325 1275);
WIRE 17 -1 (-5700 1275)(-5500 1275);
WIRE 17 -1 (-5900 1275)(-5700 1275);
WIRE 17 -1 (-6100 1275)(-5900 1275);
FORCEPROP 2 LAST SIG_NAME P3E_CPU0_PE1_PCH_TXN<7:0>
J 0
(-6035 1235);
DISPLAY 0.617021 (-6035 1235);
PAINT ORANGE (-6035 1235);
WIRE 17 -1 (-6300 1275)(-6100 1275);
WIRE 17 -1 (-6500 1275)(-6300 1275);
WIRE 17 -1 (-6700 1275)(-6500 1275);
WIRE 17 -1 (-6900 1275)(-6700 1275);
WIRE 17 -1 (-7050 2175)(-6950 2175);
FORCEPROP 2 LAST SIG_NAME P3E_CPU0_PE1_SS_TXN<7:0>
J 0
(-7035 2185);
DISPLAY 0.617021 (-7035 2185);
PAINT ORANGE (-7035 2185);
WIRE 17 -1 (-6950 2175)(-6750 2175);
WIRE 17 -1 (-6750 2175)(-6550 2175);
WIRE 17 -1 (-6550 2175)(-6350 2175);
WIRE 17 -1 (-6350 2175)(-6150 2175);
WIRE 17 -1 (-6150 2175)(-5950 2175);
WIRE 17 -1 (-5950 2175)(-5750 2175);
WIRE 17 -1 (-5750 2175)(-5550 2175);
WIRE 17 -1 (-5675 3375)(-5475 3375);
WIRE 17 -1 (-5475 3375)(-5275 3375);
WIRE 17 -1 (-5275 3375)(-5075 3375);
WIRE 17 -1 (-5075 3375)(-4875 3375);
WIRE 17 -1 (-4875 3375)(-4675 3375);
FORCEPROP 2 LAST SIG_NAME P3E_CPU0_PE1_SS_C_TXN<7:0>
J 0
(-4735 3335);
DISPLAY 0.617021 (-4735 3335);
PAINT ORANGE (-4735 3335);
WIRE 17 -1 (-4275 3375)(-4100 3375);
WIRE 17 -1 (-4675 3375)(-4475 3375);
WIRE 17 -1 (-4475 3375)(-4275 3375);
WIRE 17 -1 (-5900 3275)(-5675 3275);
FORCEPROP 2 LAST SIG_NAME P3E_CPU0_PE1_SS_TXP<7:0>
J 0
(-5860 3285);
DISPLAY 0.617021 (-5860 3285);
PAINT ORANGE (-5860 3285);
WIRE 17 -1 (-5675 3275)(-5475 3275);
WIRE 17 -1 (-5475 3275)(-5275 3275);
WIRE 17 -1 (-5275 3275)(-5075 3275);
WIRE 17 -1 (-5075 3275)(-4875 3275);
WIRE 17 -1 (-4875 3275)(-4675 3275);
WIRE 17 -1 (-4675 3275)(-4475 3275);
WIRE 17 -1 (-4475 3275)(-4275 3275);
WIRE 17 -1 (-800 3525)(-725 3525);
WIRE 17 -1 (-1000 3525)(-800 3525);
WIRE 17 -1 (-2200 3525)(-2000 3525);
WIRE 17 -1 (-2000 3525)(-1800 3525);
WIRE 17 -1 (-1200 3525)(-1000 3525);
WIRE 17 -1 (-1400 3525)(-1200 3525);
WIRE 17 -1 (-1800 3525)(-1600 3525);
WIRE 17 -1 (-1600 3525)(-1400 3525);
FORCEPROP 2 LAST SIG_NAME P3E_CPU0_PE1_SS_RXN<7:0>
J 0
(-1385 3485);
DISPLAY 0.617021 (-1385 3485);
PAINT ORANGE (-1385 3485);
WIRE 17 -1 (-1025 3400)(-825 3400);
WIRE 17 -1 (-1225 3400)(-1025 3400);
WIRE 17 -1 (-1425 3400)(-1225 3400);
WIRE 17 -1 (-1625 3400)(-1425 3400);
WIRE 17 -1 (-1825 3400)(-1625 3400);
WIRE 17 -1 (-2025 3400)(-1825 3400);
WIRE 17 -1 (-2325 3400)(-2225 3400);
FORCEPROP 2 LAST SIG_NAME P3E_CPU0_PE1_SS_R_RXP<7:0>
J 0
(-2285 3410);
DISPLAY 0.617021 (-2285 3410);
PAINT ORANGE (-2285 3410);
WIRE 17 -1 (-2225 3400)(-2025 3400);
WIRE 17 -1 (-4225 2375)(-4075 2375);
WIRE 17 -1 (-4425 2375)(-4225 2375);
WIRE 17 -1 (-5625 2375)(-5425 2375);
WIRE 17 -1 (-5425 2375)(-5225 2375);
WIRE 17 -1 (-4625 2375)(-4425 2375);
WIRE 17 -1 (-4825 2375)(-4625 2375);
FORCEPROP 2 LAST SIG_NAME P3E_CPU0_PE1_SS_C_TXP<7:0>
J 0
(-4685 2335);
DISPLAY 0.617021 (-4685 2335);
PAINT ORANGE (-4685 2335);
WIRE 17 -1 (-5225 2375)(-5025 2375);
WIRE 17 -1 (-5025 2375)(-4825 2375);
WIRE 17 -1 (-2175 2500)(-1975 2500);
WIRE 17 -1 (-775 2500)(-650 2500);
WIRE 17 -1 (-1975 2500)(-1775 2500);
WIRE 17 -1 (-1775 2500)(-1575 2500);
WIRE 17 -1 (-975 2500)(-775 2500);
WIRE 17 -1 (-1175 2500)(-975 2500);
WIRE 17 -1 (-1575 2500)(-1375 2500);
FORCEPROP 2 LAST SIG_NAME P3E_CPU0_PE1_SS_RXP<7:0>
J 0
(-1435 2460);
DISPLAY 0.617021 (-1435 2460);
PAINT ORANGE (-1435 2460);
WIRE 17 -1 (-1375 2500)(-1175 2500);
WIRE 17 -1 (-1050 4425)(-850 4425);
WIRE 17 -1 (-1250 4425)(-1050 4425);
WIRE 17 -1 (-1450 4425)(-1250 4425);
WIRE 17 -1 (-1650 4425)(-1450 4425);
WIRE 17 -1 (-1850 4425)(-1650 4425);
WIRE 17 -1 (-2050 4425)(-1850 4425);
WIRE 17 -1 (-2450 4425)(-2250 4425);
FORCEPROP 2 LAST SIG_NAME P3E_CPU0_PE1_SS_R_RXN<7:0>
J 0
(-2410 4435);
DISPLAY 0.617021 (-2410 4435);
PAINT ORANGE (-2410 4435);
WIRE 17 -1 (-2250 4425)(-2050 4425);
WIRE 17 -1 (-4525 4275)(-4325 4275);
WIRE 17 -1 (-4725 4275)(-4525 4275);
WIRE 17 -1 (-4925 4275)(-4725 4275);
WIRE 17 -1 (-5125 4275)(-4925 4275);
WIRE 17 -1 (-5325 4275)(-5125 4275);
WIRE 17 -1 (-5525 4275)(-5325 4275);
WIRE 17 -1 (-5950 4275)(-5725 4275);
FORCEPROP 2 LAST SIG_NAME P3E_CPU0_PE1_SS_TXN<7:0>
J 0
(-5885 4285);
DISPLAY 0.617021 (-5885 4285);
PAINT ORANGE (-5885 4285);
WIRE 17 -1 (-5725 4275)(-5525 4275);
WIRE 17 -1 (-2175 2125)(-1975 2125);
WIRE 17 -1 (-2375 2125)(-2175 2125);
WIRE 17 -1 (-2575 2125)(-2375 2125);
WIRE 17 -1 (-2775 2125)(-2575 2125);
WIRE 17 -1 (-2975 2125)(-2775 2125);
WIRE 17 -1 (-3175 2125)(-2975 2125);
WIRE 17 -1 (-3475 2125)(-3375 2125);
FORCEPROP 2 LAST SIG_NAME P3E_CPU0_PE1_PCH_RXN<7:0>
J 0
(-3435 2135);
DISPLAY 0.617021 (-3435 2135);
PAINT ORANGE (-3435 2135);
WIRE 17 -1 (-3375 2125)(-3175 2125);
WIRE 17 -1 (-6850 275)(-6650 275);
WIRE 17 -1 (-6650 275)(-6450 275);
WIRE 17 -1 (-6450 275)(-6250 275);
WIRE 17 -1 (-6250 275)(-6050 275);
FORCEPROP 2 LAST SIG_NAME P3E_CPU0_PE1_PCH_TXP<7:0>
J 0
(-6085 235);
DISPLAY 0.617021 (-6085 235);
PAINT ORANGE (-6085 235);
WIRE 17 -1 (-6050 275)(-5850 275);
WIRE 17 -1 (-5450 275)(-5300 275);
WIRE 17 -1 (-5850 275)(-5650 275);
WIRE 17 -1 (-5650 275)(-5450 275);
WIRE 17 -1 (-1875 225)(-1725 225);
WIRE 17 -1 (-2075 225)(-1875 225);
WIRE 17 -1 (-2275 225)(-2075 225);
WIRE 17 -1 (-2475 225)(-2275 225);
WIRE 17 -1 (-2675 225)(-2475 225);
FORCEPROP 2 LAST SIG_NAME P3E_CPU0_PE1_SS_RXP<7:0>
J 0
(-2510 185);
DISPLAY 0.617021 (-2510 185);
PAINT ORANGE (-2510 185);
WIRE 17 -1 (-2875 225)(-2675 225);
WIRE 17 -1 (-3075 225)(-2875 225);
WIRE 17 -1 (-3275 225)(-3075 225);
WIRE 17 -1 (-2125 1125)(-1925 1125);
WIRE 17 -1 (-2325 1125)(-2125 1125);
WIRE 17 -1 (-2525 1125)(-2325 1125);
WIRE 17 -1 (-3425 1125)(-3325 1125);
FORCEPROP 2 LAST SIG_NAME P3E_CPU0_PE1_PCH_RXP<7:0>
J 0
(-3385 1135);
DISPLAY 0.617021 (-3385 1135);
PAINT ORANGE (-3385 1135);
WIRE 17 -1 (-2725 1125)(-2525 1125);
WIRE 17 -1 (-2925 1125)(-2725 1125);
WIRE 17 -1 (-3325 1125)(-3125 1125);
WIRE 17 -1 (-3125 1125)(-2925 1125);
WIRE 16 -1 (-2100 1025)(-2100 625);
WIRE 16 -1 (-2300 775)(-2300 325);
WIRE 16 -1 (-2700 775)(-2700 325);
WIRE 16 -1 (-2500 425)(-2500 325);
WIRE 16 -1 (-2900 425)(-2900 325);
WIRE 16 -1 (-5675 1075)(-5675 675);
WIRE 16 -1 (-5725 2075)(-5725 1675);
WIRE 16 -1 (-4500 4175)(-4500 3800);
WIRE 16 -1 (-825 4325)(-825 4225);
WIRE 16 -1 (-1025 4325)(-1025 3925);
WIRE 16 -1 (-1225 4025)(-1225 3625);
WIRE 16 -1 (-1825 4325)(-1825 3925);
WIRE 16 -1 (-1625 4325)(-1625 4225);
WIRE 16 -1 (-1200 3300)(-1200 3200);
WIRE 16 -1 (-2000 3300)(-2000 3200);
WIRE 16 -1 (-1800 2700)(-1800 2600);
WIRE 16 -1 (-1600 3300)(-1600 3200);
WIRE 16 -1 (-1400 2700)(-1400 2600);
WIRE 16 -1 (-1000 2700)(-1000 2600);
WIRE 16 -1 (-800 3300)(-800 3200);
WIRE 16 -1 (-2225 3725)(-2225 3625);
WIRE 16 -1 (-2025 4325)(-2025 4225);
WIRE 16 -1 (-1425 3725)(-1425 3625);
WIRE 16 -1 (-1425 4325)(-1425 3925);
WIRE 16 -1 (-1225 4325)(-1225 4225);
WIRE 16 -1 (-4300 4075)(-4300 4175);
WIRE 16 -1 (-4700 4075)(-4700 4175);
WIRE 16 -1 (-5100 3875)(-5100 3475);
WIRE 16 -1 (-5100 4175)(-5100 4075);
WIRE 16 -1 (-5500 4175)(-5500 4075);
WIRE 16 -1 (-5300 3575)(-5300 3475);
WIRE 16 -1 (-5700 3575)(-5700 3475);
WIRE 16 -1 (-6875 475)(-6875 375);
WIRE 16 -1 (-6675 775)(-6675 375);
WIRE 16 -1 (-6475 475)(-6475 375);
WIRE 16 -1 (-6275 775)(-6275 375);
WIRE 16 -1 (-6875 1075)(-6875 675);
WIRE 16 -1 (-6675 1075)(-6675 975);
WIRE 16 -1 (-6275 1075)(-6275 975);
WIRE 16 -1 (-6925 1475)(-6925 1375);
WIRE 16 -1 (-6925 2075)(-6925 1675);
WIRE 16 -1 (-6725 2075)(-6725 1975);
WIRE 16 -1 (-6075 475)(-6075 375);
WIRE 16 -1 (-5675 475)(-5675 375);
WIRE 16 -1 (-5875 775)(-5875 375);
WIRE 16 -1 (-5475 1075)(-5475 975);
WIRE 16 -1 (-6125 1475)(-6125 1375);
WIRE 16 -1 (-5725 1475)(-5725 1375);
WIRE 16 -1 (-5925 2000)(-5925 2075);
WIRE 16 -1 (-3300 1025)(-3300 625);
WIRE 16 -1 (-2550 1425)(-2550 1325);
WIRE 16 -1 (-2950 1425)(-2950 1325);
WIRE 16 -1 (-3350 1425)(-3350 1325);
WIRE 16 -1 (-6525 1475)(-6525 1375);
WIRE 16 -1 (-6075 1075)(-6075 675);
WIRE 16 -1 (-6475 1075)(-6475 675);
WIRE 16 -1 (-6525 2075)(-6525 1675);
WIRE 16 -1 (-6325 1975)(-6325 2075);
WIRE 16 -1 (-6125 2075)(-6125 1675);
WIRE 16 -1 (-5300 4175)(-5300 3775);
WIRE 16 -1 (-4900 4175)(-4900 3775);
WIRE 16 -1 (-4250 3175)(-4250 3075);
WIRE 16 -1 (-4500 3600)(-4500 3475);
WIRE 16 -1 (-4450 2575)(-4450 2475);
WIRE 16 -1 (-4250 2875)(-4250 2475);
WIRE 16 -1 (-4650 2875)(-4650 2475);
WIRE 16 -1 (-4850 2575)(-4850 2475);
WIRE 16 -1 (-5050 3175)(-5050 3075);
WIRE 16 -1 (-5250 3175)(-5250 2775);
WIRE 16 -1 (-5250 2575)(-5250 2475);
WIRE 16 -1 (-5450 3175)(-5450 3075);
WIRE 16 -1 (-5450 2875)(-5450 2475);
WIRE 16 -1 (-5650 2575)(-5650 2475);
WIRE 16 -1 (-1025 3725)(-1025 3625);
WIRE 16 -1 (-2025 4025)(-2025 3625);
WIRE 16 -1 (-2200 2700)(-2200 2600);
WIRE 16 -1 (-2550 2025)(-2550 1625);
WIRE 16 -1 (-1950 2025)(-1950 1975);
WIRE 16 -1 (-3150 2025)(-3150 1975);
WIRE 16 -1 (-2350 2025)(-2350 1975);
WIRE 16 -1 (-2750 2025)(-2750 1975);
WIRE 16 -1 (-2150 2025)(-2150 1625);
WIRE 16 -1 (-2350 1775)(-2350 1325);
WIRE 16 -1 (-2950 2025)(-2950 1625);
WIRE 16 -1 (-1900 1025)(-1900 975);
WIRE 16 -1 (-3100 1025)(-3100 975);
WIRE 16 -1 (-2700 1025)(-2700 975);
WIRE 16 -1 (-2300 1025)(-2300 975);
WIRE 16 -1 (-1900 775)(-1900 325);
WIRE 16 -1 (-2100 425)(-2100 325);
WIRE 16 -1 (-2500 1025)(-2500 625);
WIRE 16 -1 (-2900 1025)(-2900 625);
WIRE 16 -1 (-3100 775)(-3100 325);
WIRE 16 -1 (-3300 425)(-3300 325);
WIRE 16 -1 (-5475 775)(-5475 375);
WIRE 16 -1 (-3350 2025)(-3350 1625);
WIRE 16 -1 (-800 3000)(-800 2600);
WIRE 16 -1 (-1600 3000)(-1600 2600);
WIRE 16 -1 (-1800 3300)(-1800 2900);
WIRE 16 -1 (-1400 3300)(-1400 2900);
WIRE 16 -1 (-4900 3575)(-4900 3475);
WIRE 16 -1 (-5500 3875)(-5500 3475);
WIRE 16 -1 (-5700 4175)(-5700 3775);
WIRE 16 -1 (-2000 3000)(-2000 2600);
WIRE 16 -1 (-2225 4325)(-2225 3925);
WIRE 16 -1 (-825 4025)(-825 3625);
WIRE 16 -1 (-1200 3000)(-1200 2600);
WIRE 16 -1 (-1000 3300)(-1000 2900);
WIRE 16 -1 (-5650 3175)(-5650 2775);
WIRE 16 -1 (-5050 2875)(-5050 2475);
WIRE 16 -1 (-2200 3300)(-2200 2900);
WIRE 16 -1 (-4700 3475)(-4700 3875);
WIRE 16 -1 (-1825 3725)(-1825 3625);
WIRE 16 -1 (-1625 4025)(-1625 3625);
WIRE 16 -1 (-4650 3175)(-4650 3075);
WIRE 16 -1 (-4850 3175)(-4850 2775);
WIRE 16 -1 (-4450 3175)(-4450 2775);
WIRE 16 -1 (-4300 3475)(-4300 3875);
WIRE 16 -1 (-5525 2075)(-5525 1975);
WIRE 16 -1 (-6325 1375)(-6325 1775);
WIRE 16 -1 (-5925 1375)(-5925 1800);
WIRE 16 -1 (-2750 1775)(-2750 1325);
WIRE 16 -1 (-3150 1775)(-3150 1325);
WIRE 16 -1 (-5525 1775)(-5525 1375);
WIRE 16 -1 (-6725 1775)(-6725 1375);
WIRE 16 -1 (-5875 1075)(-5875 975);
WIRE 16 273 (-7700 2250)(0 2250);
WIRE 16 -1 (-2150 1425)(-2150 1325);
WIRE 16 -1 (-1950 1775)(-1950 1325);
FORCENOTE
TO CPU0
(-1325 700) 0;
DISPLAY LEFT (-1325 700);
DISPLAY 1.021277 (-1325 700);
PAINT PURPLE (-1325 700);
FORCENOTE
FROM X24 SUPER SLOT
(-3250 3925) 0;
DISPLAY LEFT (-3250 3925);
DISPLAY 1.021277 (-3250 3925);
PAINT PURPLE (-3250 3925);
FORCENOTE
CPU0 TO PCIE X24 SLOT TX CAPS
(-6025 4375) 0;
DISPLAY LEFT (-6025 4375);
DISPLAY 1.021277 (-6025 4375);
PAINT PURPLE (-6025 4375);
FORCENOTE
CPU0 <-> X24 SUPER SLOT
(-7700 2400) 0;
DISPLAY LEFT (-7700 2400);
DISPLAY 2.000000 (-7700 2400);
PAINT PURPLE (-7700 2400);
FORCENOTE
FROM CPU 0
(-7725 1625) 0;
DISPLAY LEFT (-7725 1625);
DISPLAY 1.021277 (-7725 1625);
PAINT PURPLE (-7725 1625);
FORCENOTE
DE NOTE:
(-6025 4450) 0;
DISPLAY LEFT (-6025 4450);
DISPLAY 1.021277 (-6025 4450);
PAINT PURPLE (-6025 4450);
FORCENOTE
FROM CPU 0
(-6900 3725) 0;
DISPLAY LEFT (-6900 3725);
DISPLAY 1.021277 (-6900 3725);
PAINT PURPLE (-6900 3725);
FORCENOTE
TO X24 SUPER SLOT
(-3925 3100) 0;
DISPLAY LEFT (-3925 3100);
DISPLAY 1.021277 (-3925 3100);
PAINT PURPLE (-3925 3100);
FORCENOTE
CPU0 <-> PCH PCIEUP
(-1450 2000) 0;
DISPLAY LEFT (-1450 2000);
DISPLAY 2.000000 (-1450 2000);
PAINT PURPLE (-1450 2000);
FORCENOTE
TO PCH PCIEUP
(-5050 925) 0;
DISPLAY LEFT (-5050 925);
DISPLAY 1.021277 (-5050 925);
PAINT PURPLE (-5050 925);
FORCENOTE
TO CPU0
(-300 3025) 0;
DISPLAY LEFT (-300 3025);
DISPLAY 1.021277 (-300 3025);
PAINT PURPLE (-300 3025);
FORCENOTE
FROM PCH PCIEUP 
(-4400 1750) 0;
DISPLAY LEFT (-4400 1750);
DISPLAY 1.021277 (-4400 1750);
PAINT PURPLE (-4400 1750);
QUIT
